FILE_TYPE = MACRO_DRAWING;
SET COLOR_WIRE YELLOW;
SET COLOR_PROP MONO;
SET COLOR_DOT WHITE;
SET COLOR_ARC YELLOW;
SET COLOR_BODY GREEN;
SET COLOR_NOTE MONO;
SET PROP_DISPLAY VALUE;
SET PAGE_NUMBER P25;
FORCEADD OFFPAGE..5
(-6425 550);
FORCEPROP 2 LAST $XR0 47 
J 0
(-6679 550);
DISPLAY 0.638298 (-6679 550);
PAINT MONO (-6679 550);
FORCEPROP 2 LAST $XR1 48 
J 0
(-6769 550);
DISPLAY 0.638298 (-6769 550);
PAINT MONO (-6769 550);
FORCEPROP 2 LAST CDS_LIB mstr_standard
J 0
(-6425 550);
PAINT MONO (-6425 550);
DISPLAY INVISIBLE (-6425 550);
FORCEPROP 1 LAST OFFPAGE TRUE
J 0
(-6100 425);
DISPLAY 1.170213 (-6100 425);
PAINT GREEN (-6100 425);
DISPLAY INVISIBLE (-6100 425);
FORCEPROP 1 LAST COMMENT_BODY TRUE
J 0
(-6325 475);
DISPLAY 1.170213 (-6325 475);
PAINT GREEN (-6325 475);
DISPLAY INVISIBLE (-6325 475);
FORCEPROP 2 LAST PATH I1
J 0
(-6375 625);
DISPLAY 1.021277 (-6375 625);
PAINT ORANGE (-6375 625);
DISPLAY INVISIBLE (-6375 625);
FORCEADD TAP..6
(-5575 900);
FORCEPROP 3 LASTPIN (-5525 900) SIG_NAME M_C_CLK_DP<1>
J 0
(-5515 910);
DISPLAY 0.659574 (-5515 910);
PAINT MONO (-5515 910);
DISPLAY INVISIBLE (-5515 910);
FORCEPROP 1 LASTPIN (-5525 900) BN 1
J 0
(-5577 908);
DISPLAY 0.617021 (-5577 908);
PAINT PINK (-5577 908);
FORCEPROP 2 LAST CDS_LIB mstr_standard
J 0
(-5575 900);
PAINT MONO (-5575 900);
DISPLAY INVISIBLE (-5575 900);
FORCEPROP 1 LAST BODY_TYPE PLUMBING
J 0
(-5575 850);
DISPLAY 1.595745 (-5575 850);
PAINT GREEN (-5575 850);
DISPLAY INVISIBLE (-5575 850);
FORCEPROP 1 LAST HDL_TAP TRUE
J 0
(-5250 775);
DISPLAY 1.595745 (-5250 775);
PAINT GREEN (-5250 775);
DISPLAY INVISIBLE (-5250 775);
FORCEPROP 1 LAST PATH I10
J 0
(-5577 900);
DISPLAY 0.872340 (-5577 900);
PAINT GREEN (-5577 900);
DISPLAY INVISIBLE (-5577 900);
FORCEADD TAP..6
R 2
(-2850 1500);
FORCEPROP 3 LASTPIN (-2900 1500) SIG_NAME M_C_ODT<1>
J 0
(-2890 1510);
DISPLAY 0.659574 (-2890 1510);
PAINT MONO (-2890 1510);
DISPLAY INVISIBLE (-2890 1510);
FORCEPROP 1 LASTPIN (-2900 1500) BN 1
J 2
(-2848 1508);
DISPLAY 0.617021 (-2848 1508);
PAINT PINK (-2848 1508);
FORCEPROP 2 LAST CDS_LIB mstr_standard
J 0
(-2850 1500);
PAINT MONO (-2850 1500);
DISPLAY INVISIBLE (-2850 1500);
FORCEPROP 1 LAST BODY_TYPE PLUMBING
J 2
(-2850 1450);
DISPLAY 1.595745 (-2850 1450);
PAINT GREEN (-2850 1450);
DISPLAY INVISIBLE (-2850 1450);
FORCEPROP 1 LAST HDL_TAP TRUE
J 2
(-3175 1375);
DISPLAY 1.595745 (-3175 1375);
PAINT GREEN (-3175 1375);
DISPLAY INVISIBLE (-3175 1375);
FORCEPROP 1 LAST PATH I100
J 2
(-2848 1500);
DISPLAY 0.872340 (-2848 1500);
PAINT GREEN (-2848 1500);
DISPLAY INVISIBLE (-2848 1500);
FORCEADD TAP..6
R 2
(-2850 1550);
FORCEPROP 3 LASTPIN (-2900 1550) SIG_NAME M_C_ODT<2>
J 0
(-2890 1560);
DISPLAY 0.659574 (-2890 1560);
PAINT MONO (-2890 1560);
DISPLAY INVISIBLE (-2890 1560);
FORCEPROP 1 LASTPIN (-2900 1550) BN 2
J 2
(-2848 1558);
DISPLAY 0.617021 (-2848 1558);
PAINT PINK (-2848 1558);
FORCEPROP 2 LAST CDS_LIB mstr_standard
J 0
(-2850 1550);
PAINT MONO (-2850 1550);
DISPLAY INVISIBLE (-2850 1550);
FORCEPROP 1 LAST BODY_TYPE PLUMBING
J 2
(-2850 1500);
DISPLAY 1.595745 (-2850 1500);
PAINT GREEN (-2850 1500);
DISPLAY INVISIBLE (-2850 1500);
FORCEPROP 1 LAST HDL_TAP TRUE
J 2
(-3175 1425);
DISPLAY 1.595745 (-3175 1425);
PAINT GREEN (-3175 1425);
DISPLAY INVISIBLE (-3175 1425);
FORCEPROP 1 LAST PATH I101
J 2
(-2848 1550);
DISPLAY 0.872340 (-2848 1550);
PAINT GREEN (-2848 1550);
DISPLAY INVISIBLE (-2848 1550);
FORCEADD TAP..6
R 2
(-2850 1600);
FORCEPROP 3 LASTPIN (-2900 1600) SIG_NAME M_C_ODT<3>
J 0
(-2890 1610);
DISPLAY 0.659574 (-2890 1610);
PAINT MONO (-2890 1610);
DISPLAY INVISIBLE (-2890 1610);
FORCEPROP 1 LASTPIN (-2900 1600) BN 3
J 2
(-2848 1608);
DISPLAY 0.617021 (-2848 1608);
PAINT PINK (-2848 1608);
FORCEPROP 2 LAST CDS_LIB mstr_standard
J 0
(-2850 1600);
PAINT MONO (-2850 1600);
DISPLAY INVISIBLE (-2850 1600);
FORCEPROP 1 LAST BODY_TYPE PLUMBING
J 2
(-2850 1550);
DISPLAY 1.595745 (-2850 1550);
PAINT GREEN (-2850 1550);
DISPLAY INVISIBLE (-2850 1550);
FORCEPROP 1 LAST HDL_TAP TRUE
J 2
(-3175 1475);
DISPLAY 1.595745 (-3175 1475);
PAINT GREEN (-3175 1475);
DISPLAY INVISIBLE (-3175 1475);
FORCEPROP 1 LAST PATH I102
J 2
(-2848 1600);
DISPLAY 0.872340 (-2848 1600);
PAINT GREEN (-2848 1600);
DISPLAY INVISIBLE (-2848 1600);
FORCEADD TAP..6
R 2
(-2850 1700);
FORCEPROP 3 LASTPIN (-2900 1700) SIG_NAME M_C_CKE<0>
J 0
(-2890 1710);
DISPLAY 0.659574 (-2890 1710);
PAINT MONO (-2890 1710);
DISPLAY INVISIBLE (-2890 1710);
FORCEPROP 1 LASTPIN (-2900 1700) BN 0
J 2
(-2848 1708);
DISPLAY 0.617021 (-2848 1708);
PAINT PINK (-2848 1708);
FORCEPROP 2 LAST CDS_LIB mstr_standard
J 0
(-2850 1700);
PAINT MONO (-2850 1700);
DISPLAY INVISIBLE (-2850 1700);
FORCEPROP 1 LAST BODY_TYPE PLUMBING
J 2
(-2850 1650);
DISPLAY 1.595745 (-2850 1650);
PAINT GREEN (-2850 1650);
DISPLAY INVISIBLE (-2850 1650);
FORCEPROP 1 LAST HDL_TAP TRUE
J 2
(-3175 1575);
DISPLAY 1.595745 (-3175 1575);
PAINT GREEN (-3175 1575);
DISPLAY INVISIBLE (-3175 1575);
FORCEPROP 1 LAST PATH I103
J 2
(-2848 1700);
DISPLAY 0.872340 (-2848 1700);
PAINT GREEN (-2848 1700);
DISPLAY INVISIBLE (-2848 1700);
FORCEADD TAP..6
R 2
(-2850 1750);
FORCEPROP 3 LASTPIN (-2900 1750) SIG_NAME M_C_CKE<1>
J 0
(-2890 1760);
DISPLAY 0.659574 (-2890 1760);
PAINT MONO (-2890 1760);
DISPLAY INVISIBLE (-2890 1760);
FORCEPROP 1 LASTPIN (-2900 1750) BN 1
J 2
(-2848 1758);
DISPLAY 0.617021 (-2848 1758);
PAINT PINK (-2848 1758);
FORCEPROP 2 LAST CDS_LIB mstr_standard
J 0
(-2850 1750);
PAINT MONO (-2850 1750);
DISPLAY INVISIBLE (-2850 1750);
FORCEPROP 1 LAST BODY_TYPE PLUMBING
J 2
(-2850 1700);
DISPLAY 1.595745 (-2850 1700);
PAINT GREEN (-2850 1700);
DISPLAY INVISIBLE (-2850 1700);
FORCEPROP 1 LAST HDL_TAP TRUE
J 2
(-3175 1625);
DISPLAY 1.595745 (-3175 1625);
PAINT GREEN (-3175 1625);
DISPLAY INVISIBLE (-3175 1625);
FORCEPROP 1 LAST PATH I104
J 2
(-2848 1750);
DISPLAY 0.872340 (-2848 1750);
PAINT GREEN (-2848 1750);
DISPLAY INVISIBLE (-2848 1750);
FORCEADD TAP..6
R 2
(-2850 1800);
FORCEPROP 3 LASTPIN (-2900 1800) SIG_NAME M_C_CKE<2>
J 0
(-2890 1810);
DISPLAY 0.659574 (-2890 1810);
PAINT MONO (-2890 1810);
DISPLAY INVISIBLE (-2890 1810);
FORCEPROP 1 LASTPIN (-2900 1800) BN 2
J 2
(-2848 1808);
DISPLAY 0.617021 (-2848 1808);
PAINT PINK (-2848 1808);
FORCEPROP 2 LAST CDS_LIB mstr_standard
J 0
(-2850 1800);
PAINT MONO (-2850 1800);
DISPLAY INVISIBLE (-2850 1800);
FORCEPROP 1 LAST BODY_TYPE PLUMBING
J 2
(-2850 1750);
DISPLAY 1.595745 (-2850 1750);
PAINT GREEN (-2850 1750);
DISPLAY INVISIBLE (-2850 1750);
FORCEPROP 1 LAST HDL_TAP TRUE
J 2
(-3175 1675);
DISPLAY 1.595745 (-3175 1675);
PAINT GREEN (-3175 1675);
DISPLAY INVISIBLE (-3175 1675);
FORCEPROP 1 LAST PATH I105
J 2
(-2848 1800);
DISPLAY 0.872340 (-2848 1800);
PAINT GREEN (-2848 1800);
DISPLAY INVISIBLE (-2848 1800);
FORCEADD TAP..6
R 2
(-2850 1850);
FORCEPROP 3 LASTPIN (-2900 1850) SIG_NAME M_C_CKE<3>
J 0
(-2890 1860);
DISPLAY 0.659574 (-2890 1860);
PAINT MONO (-2890 1860);
DISPLAY INVISIBLE (-2890 1860);
FORCEPROP 1 LASTPIN (-2900 1850) BN 3
J 2
(-2848 1858);
DISPLAY 0.617021 (-2848 1858);
PAINT PINK (-2848 1858);
FORCEPROP 2 LAST CDS_LIB mstr_standard
J 0
(-2850 1850);
PAINT MONO (-2850 1850);
DISPLAY INVISIBLE (-2850 1850);
FORCEPROP 1 LAST BODY_TYPE PLUMBING
J 2
(-2850 1800);
DISPLAY 1.595745 (-2850 1800);
PAINT GREEN (-2850 1800);
DISPLAY INVISIBLE (-2850 1800);
FORCEPROP 1 LAST HDL_TAP TRUE
J 2
(-3175 1725);
DISPLAY 1.595745 (-3175 1725);
PAINT GREEN (-3175 1725);
DISPLAY INVISIBLE (-3175 1725);
FORCEPROP 1 LAST PATH I106
J 2
(-2848 1850);
DISPLAY 0.872340 (-2848 1850);
PAINT GREEN (-2848 1850);
DISPLAY INVISIBLE (-2848 1850);
FORCEADD TAP..6
R 2
(-2850 1950);
FORCEPROP 3 LASTPIN (-2900 1950) SIG_NAME M_C_MA<0>
J 0
(-2890 1960);
DISPLAY 0.659574 (-2890 1960);
PAINT MONO (-2890 1960);
DISPLAY INVISIBLE (-2890 1960);
FORCEPROP 1 LASTPIN (-2900 1950) BN 0
J 2
(-2848 1958);
DISPLAY 0.617021 (-2848 1958);
PAINT PINK (-2848 1958);
FORCEPROP 2 LAST CDS_LIB mstr_standard
J 0
(-2850 1950);
PAINT MONO (-2850 1950);
DISPLAY INVISIBLE (-2850 1950);
FORCEPROP 1 LAST BODY_TYPE PLUMBING
J 2
(-2850 1900);
DISPLAY 1.595745 (-2850 1900);
PAINT GREEN (-2850 1900);
DISPLAY INVISIBLE (-2850 1900);
FORCEPROP 1 LAST HDL_TAP TRUE
J 2
(-3175 1825);
DISPLAY 1.595745 (-3175 1825);
PAINT GREEN (-3175 1825);
DISPLAY INVISIBLE (-3175 1825);
FORCEPROP 1 LAST PATH I107
J 2
(-2848 1950);
DISPLAY 0.872340 (-2848 1950);
PAINT GREEN (-2848 1950);
DISPLAY INVISIBLE (-2848 1950);
FORCEADD TAP..6
R 2
(-2850 2050);
FORCEPROP 3 LASTPIN (-2900 2050) SIG_NAME M_C_MA<2>
J 0
(-2890 2060);
DISPLAY 0.659574 (-2890 2060);
PAINT MONO (-2890 2060);
DISPLAY INVISIBLE (-2890 2060);
FORCEPROP 1 LASTPIN (-2900 2050) BN 2
J 2
(-2848 2058);
DISPLAY 0.617021 (-2848 2058);
PAINT PINK (-2848 2058);
FORCEPROP 2 LAST CDS_LIB mstr_standard
J 0
(-2850 2050);
PAINT MONO (-2850 2050);
DISPLAY INVISIBLE (-2850 2050);
FORCEPROP 1 LAST BODY_TYPE PLUMBING
J 2
(-2850 2000);
DISPLAY 1.595745 (-2850 2000);
PAINT GREEN (-2850 2000);
DISPLAY INVISIBLE (-2850 2000);
FORCEPROP 1 LAST HDL_TAP TRUE
J 2
(-3175 1925);
DISPLAY 1.595745 (-3175 1925);
PAINT GREEN (-3175 1925);
DISPLAY INVISIBLE (-3175 1925);
FORCEPROP 1 LAST PATH I108
J 2
(-2848 2050);
DISPLAY 0.872340 (-2848 2050);
PAINT GREEN (-2848 2050);
DISPLAY INVISIBLE (-2848 2050);
FORCEADD TAP..6
R 2
(-2850 2000);
FORCEPROP 3 LASTPIN (-2900 2000) SIG_NAME M_C_MA<1>
J 0
(-2890 2010);
DISPLAY 0.659574 (-2890 2010);
PAINT MONO (-2890 2010);
DISPLAY INVISIBLE (-2890 2010);
FORCEPROP 1 LASTPIN (-2900 2000) BN 1
J 2
(-2848 2008);
DISPLAY 0.617021 (-2848 2008);
PAINT PINK (-2848 2008);
FORCEPROP 2 LAST CDS_LIB mstr_standard
J 0
(-2850 2000);
PAINT MONO (-2850 2000);
DISPLAY INVISIBLE (-2850 2000);
FORCEPROP 1 LAST BODY_TYPE PLUMBING
J 2
(-2850 1950);
DISPLAY 1.595745 (-2850 1950);
PAINT GREEN (-2850 1950);
DISPLAY INVISIBLE (-2850 1950);
FORCEPROP 1 LAST HDL_TAP TRUE
J 2
(-3175 1875);
DISPLAY 1.595745 (-3175 1875);
PAINT GREEN (-3175 1875);
DISPLAY INVISIBLE (-3175 1875);
FORCEPROP 1 LAST PATH I109
J 2
(-2848 2000);
DISPLAY 0.872340 (-2848 2000);
PAINT GREEN (-2848 2000);
DISPLAY INVISIBLE (-2848 2000);
FORCEADD TAP..6
(-5575 950);
FORCEPROP 3 LASTPIN (-5525 950) SIG_NAME M_C_CLK_DP<2>
J 0
(-5515 960);
DISPLAY 0.659574 (-5515 960);
PAINT MONO (-5515 960);
DISPLAY INVISIBLE (-5515 960);
FORCEPROP 1 LASTPIN (-5525 950) BN 2
J 0
(-5577 958);
DISPLAY 0.617021 (-5577 958);
PAINT PINK (-5577 958);
FORCEPROP 2 LAST CDS_LIB mstr_standard
J 0
(-5575 950);
PAINT MONO (-5575 950);
DISPLAY INVISIBLE (-5575 950);
FORCEPROP 1 LAST BODY_TYPE PLUMBING
J 0
(-5575 900);
DISPLAY 1.595745 (-5575 900);
PAINT GREEN (-5575 900);
DISPLAY INVISIBLE (-5575 900);
FORCEPROP 1 LAST HDL_TAP TRUE
J 0
(-5250 825);
DISPLAY 1.595745 (-5250 825);
PAINT GREEN (-5250 825);
DISPLAY INVISIBLE (-5250 825);
FORCEPROP 1 LAST PATH I11
J 0
(-5577 950);
DISPLAY 0.872340 (-5577 950);
PAINT GREEN (-5577 950);
DISPLAY INVISIBLE (-5577 950);
FORCEADD TAP..6
R 2
(-2850 2100);
FORCEPROP 3 LASTPIN (-2900 2100) SIG_NAME M_C_MA<3>
J 0
(-2890 2110);
DISPLAY 0.659574 (-2890 2110);
PAINT MONO (-2890 2110);
DISPLAY INVISIBLE (-2890 2110);
FORCEPROP 1 LASTPIN (-2900 2100) BN 3
J 2
(-2848 2108);
DISPLAY 0.617021 (-2848 2108);
PAINT PINK (-2848 2108);
FORCEPROP 2 LAST CDS_LIB mstr_standard
J 0
(-2850 2100);
PAINT MONO (-2850 2100);
DISPLAY INVISIBLE (-2850 2100);
FORCEPROP 1 LAST BODY_TYPE PLUMBING
J 2
(-2850 2050);
DISPLAY 1.595745 (-2850 2050);
PAINT GREEN (-2850 2050);
DISPLAY INVISIBLE (-2850 2050);
FORCEPROP 1 LAST HDL_TAP TRUE
J 2
(-3175 1975);
DISPLAY 1.595745 (-3175 1975);
PAINT GREEN (-3175 1975);
DISPLAY INVISIBLE (-3175 1975);
FORCEPROP 1 LAST PATH I110
J 2
(-2848 2100);
DISPLAY 0.872340 (-2848 2100);
PAINT GREEN (-2848 2100);
DISPLAY INVISIBLE (-2848 2100);
FORCEADD TAP..6
R 2
(-2850 2150);
FORCEPROP 3 LASTPIN (-2900 2150) SIG_NAME M_C_MA<4>
J 0
(-2890 2160);
DISPLAY 0.659574 (-2890 2160);
PAINT MONO (-2890 2160);
DISPLAY INVISIBLE (-2890 2160);
FORCEPROP 1 LASTPIN (-2900 2150) BN 4
J 2
(-2848 2158);
DISPLAY 0.617021 (-2848 2158);
PAINT PINK (-2848 2158);
FORCEPROP 2 LAST CDS_LIB mstr_standard
J 0
(-2850 2150);
PAINT MONO (-2850 2150);
DISPLAY INVISIBLE (-2850 2150);
FORCEPROP 1 LAST BODY_TYPE PLUMBING
J 2
(-2850 2100);
DISPLAY 1.595745 (-2850 2100);
PAINT GREEN (-2850 2100);
DISPLAY INVISIBLE (-2850 2100);
FORCEPROP 1 LAST HDL_TAP TRUE
J 2
(-3175 2025);
DISPLAY 1.595745 (-3175 2025);
PAINT GREEN (-3175 2025);
DISPLAY INVISIBLE (-3175 2025);
FORCEPROP 1 LAST PATH I111
J 2
(-2848 2150);
DISPLAY 0.872340 (-2848 2150);
PAINT GREEN (-2848 2150);
DISPLAY INVISIBLE (-2848 2150);
FORCEADD TAP..6
R 2
(-2850 2200);
FORCEPROP 3 LASTPIN (-2900 2200) SIG_NAME M_C_MA<5>
J 0
(-2890 2210);
DISPLAY 0.659574 (-2890 2210);
PAINT MONO (-2890 2210);
DISPLAY INVISIBLE (-2890 2210);
FORCEPROP 1 LASTPIN (-2900 2200) BN 5
J 2
(-2848 2208);
DISPLAY 0.617021 (-2848 2208);
PAINT PINK (-2848 2208);
FORCEPROP 2 LAST CDS_LIB mstr_standard
J 0
(-2850 2200);
PAINT MONO (-2850 2200);
DISPLAY INVISIBLE (-2850 2200);
FORCEPROP 1 LAST BODY_TYPE PLUMBING
J 2
(-2850 2150);
DISPLAY 1.595745 (-2850 2150);
PAINT GREEN (-2850 2150);
DISPLAY INVISIBLE (-2850 2150);
FORCEPROP 1 LAST HDL_TAP TRUE
J 2
(-3175 2075);
DISPLAY 1.595745 (-3175 2075);
PAINT GREEN (-3175 2075);
DISPLAY INVISIBLE (-3175 2075);
FORCEPROP 1 LAST PATH I112
J 2
(-2848 2200);
DISPLAY 0.872340 (-2848 2200);
PAINT GREEN (-2848 2200);
DISPLAY INVISIBLE (-2848 2200);
FORCEADD TAP..6
R 2
(-2850 2250);
FORCEPROP 3 LASTPIN (-2900 2250) SIG_NAME M_C_MA<6>
J 0
(-2890 2260);
DISPLAY 0.659574 (-2890 2260);
PAINT MONO (-2890 2260);
DISPLAY INVISIBLE (-2890 2260);
FORCEPROP 1 LASTPIN (-2900 2250) BN 6
J 2
(-2848 2258);
DISPLAY 0.617021 (-2848 2258);
PAINT PINK (-2848 2258);
FORCEPROP 2 LAST CDS_LIB mstr_standard
J 0
(-2850 2250);
PAINT MONO (-2850 2250);
DISPLAY INVISIBLE (-2850 2250);
FORCEPROP 1 LAST BODY_TYPE PLUMBING
J 2
(-2850 2200);
DISPLAY 1.595745 (-2850 2200);
PAINT GREEN (-2850 2200);
DISPLAY INVISIBLE (-2850 2200);
FORCEPROP 1 LAST HDL_TAP TRUE
J 2
(-3175 2125);
DISPLAY 1.595745 (-3175 2125);
PAINT GREEN (-3175 2125);
DISPLAY INVISIBLE (-3175 2125);
FORCEPROP 1 LAST PATH I113
J 2
(-2848 2250);
DISPLAY 0.872340 (-2848 2250);
PAINT GREEN (-2848 2250);
DISPLAY INVISIBLE (-2848 2250);
FORCEADD TAP..6
R 2
(-2850 2300);
FORCEPROP 3 LASTPIN (-2900 2300) SIG_NAME M_C_MA<7>
J 0
(-2890 2310);
DISPLAY 0.659574 (-2890 2310);
PAINT MONO (-2890 2310);
DISPLAY INVISIBLE (-2890 2310);
FORCEPROP 1 LASTPIN (-2900 2300) BN 7
J 2
(-2848 2308);
DISPLAY 0.617021 (-2848 2308);
PAINT PINK (-2848 2308);
FORCEPROP 2 LAST CDS_LIB mstr_standard
J 0
(-2850 2300);
PAINT MONO (-2850 2300);
DISPLAY INVISIBLE (-2850 2300);
FORCEPROP 1 LAST BODY_TYPE PLUMBING
J 2
(-2850 2250);
DISPLAY 1.595745 (-2850 2250);
PAINT GREEN (-2850 2250);
DISPLAY INVISIBLE (-2850 2250);
FORCEPROP 1 LAST HDL_TAP TRUE
J 2
(-3175 2175);
DISPLAY 1.595745 (-3175 2175);
PAINT GREEN (-3175 2175);
DISPLAY INVISIBLE (-3175 2175);
FORCEPROP 1 LAST PATH I114
J 2
(-2848 2300);
DISPLAY 0.872340 (-2848 2300);
PAINT GREEN (-2848 2300);
DISPLAY INVISIBLE (-2848 2300);
FORCEADD TAP..6
R 2
(-2850 2350);
FORCEPROP 3 LASTPIN (-2900 2350) SIG_NAME M_C_MA<8>
J 0
(-2890 2360);
DISPLAY 0.659574 (-2890 2360);
PAINT MONO (-2890 2360);
DISPLAY INVISIBLE (-2890 2360);
FORCEPROP 1 LASTPIN (-2900 2350) BN 8
J 2
(-2848 2358);
DISPLAY 0.617021 (-2848 2358);
PAINT PINK (-2848 2358);
FORCEPROP 2 LAST CDS_LIB mstr_standard
J 0
(-2850 2350);
PAINT MONO (-2850 2350);
DISPLAY INVISIBLE (-2850 2350);
FORCEPROP 1 LAST BODY_TYPE PLUMBING
J 2
(-2850 2300);
DISPLAY 1.595745 (-2850 2300);
PAINT GREEN (-2850 2300);
DISPLAY INVISIBLE (-2850 2300);
FORCEPROP 1 LAST HDL_TAP TRUE
J 2
(-3175 2225);
DISPLAY 1.595745 (-3175 2225);
PAINT GREEN (-3175 2225);
DISPLAY INVISIBLE (-3175 2225);
FORCEPROP 1 LAST PATH I115
J 2
(-2848 2350);
DISPLAY 0.872340 (-2848 2350);
PAINT GREEN (-2848 2350);
DISPLAY INVISIBLE (-2848 2350);
FORCEADD TAP..6
R 2
(-2850 2400);
FORCEPROP 3 LASTPIN (-2900 2400) SIG_NAME M_C_MA<9>
J 0
(-2890 2410);
DISPLAY 0.659574 (-2890 2410);
PAINT MONO (-2890 2410);
DISPLAY INVISIBLE (-2890 2410);
FORCEPROP 1 LASTPIN (-2900 2400) BN 9
J 2
(-2848 2408);
DISPLAY 0.617021 (-2848 2408);
PAINT PINK (-2848 2408);
FORCEPROP 2 LAST CDS_LIB mstr_standard
J 0
(-2850 2400);
PAINT MONO (-2850 2400);
DISPLAY INVISIBLE (-2850 2400);
FORCEPROP 1 LAST BODY_TYPE PLUMBING
J 2
(-2850 2350);
DISPLAY 1.595745 (-2850 2350);
PAINT GREEN (-2850 2350);
DISPLAY INVISIBLE (-2850 2350);
FORCEPROP 1 LAST HDL_TAP TRUE
J 2
(-3175 2275);
DISPLAY 1.595745 (-3175 2275);
PAINT GREEN (-3175 2275);
DISPLAY INVISIBLE (-3175 2275);
FORCEPROP 1 LAST PATH I116
J 2
(-2848 2400);
DISPLAY 0.872340 (-2848 2400);
PAINT GREEN (-2848 2400);
DISPLAY INVISIBLE (-2848 2400);
FORCEADD TAP..6
R 2
(-2850 2450);
FORCEPROP 3 LASTPIN (-2900 2450) SIG_NAME M_C_MA<10>
J 0
(-2890 2460);
DISPLAY 0.659574 (-2890 2460);
PAINT MONO (-2890 2460);
DISPLAY INVISIBLE (-2890 2460);
FORCEPROP 1 LASTPIN (-2900 2450) BN 10
J 2
(-2848 2458);
DISPLAY 0.617021 (-2848 2458);
PAINT PINK (-2848 2458);
FORCEPROP 2 LAST CDS_LIB mstr_standard
J 0
(-2850 2450);
PAINT MONO (-2850 2450);
DISPLAY INVISIBLE (-2850 2450);
FORCEPROP 1 LAST BODY_TYPE PLUMBING
J 2
(-2850 2400);
DISPLAY 1.595745 (-2850 2400);
PAINT GREEN (-2850 2400);
DISPLAY INVISIBLE (-2850 2400);
FORCEPROP 1 LAST HDL_TAP TRUE
J 2
(-3175 2325);
DISPLAY 1.595745 (-3175 2325);
PAINT GREEN (-3175 2325);
DISPLAY INVISIBLE (-3175 2325);
FORCEPROP 1 LAST PATH I117
J 2
(-2848 2450);
DISPLAY 0.872340 (-2848 2450);
PAINT GREEN (-2848 2450);
DISPLAY INVISIBLE (-2848 2450);
FORCEADD TAP..6
R 2
(-2850 2500);
FORCEPROP 3 LASTPIN (-2900 2500) SIG_NAME M_C_MA<11>
J 0
(-2890 2510);
DISPLAY 0.659574 (-2890 2510);
PAINT MONO (-2890 2510);
DISPLAY INVISIBLE (-2890 2510);
FORCEPROP 1 LASTPIN (-2900 2500) BN 11
J 2
(-2848 2508);
DISPLAY 0.617021 (-2848 2508);
PAINT PINK (-2848 2508);
FORCEPROP 2 LAST CDS_LIB mstr_standard
J 0
(-2850 2500);
PAINT MONO (-2850 2500);
DISPLAY INVISIBLE (-2850 2500);
FORCEPROP 1 LAST BODY_TYPE PLUMBING
J 2
(-2850 2450);
DISPLAY 1.595745 (-2850 2450);
PAINT GREEN (-2850 2450);
DISPLAY INVISIBLE (-2850 2450);
FORCEPROP 1 LAST HDL_TAP TRUE
J 2
(-3175 2375);
DISPLAY 1.595745 (-3175 2375);
PAINT GREEN (-3175 2375);
DISPLAY INVISIBLE (-3175 2375);
FORCEPROP 1 LAST PATH I118
J 2
(-2848 2500);
DISPLAY 0.872340 (-2848 2500);
PAINT GREEN (-2848 2500);
DISPLAY INVISIBLE (-2848 2500);
FORCEADD TAP..6
R 2
(-2850 2550);
FORCEPROP 3 LASTPIN (-2900 2550) SIG_NAME M_C_MA<12>
J 0
(-2890 2560);
DISPLAY 0.659574 (-2890 2560);
PAINT MONO (-2890 2560);
DISPLAY INVISIBLE (-2890 2560);
FORCEPROP 1 LASTPIN (-2900 2550) BN 12
J 2
(-2848 2558);
DISPLAY 0.617021 (-2848 2558);
PAINT PINK (-2848 2558);
FORCEPROP 2 LAST CDS_LIB mstr_standard
J 0
(-2850 2550);
PAINT MONO (-2850 2550);
DISPLAY INVISIBLE (-2850 2550);
FORCEPROP 1 LAST BODY_TYPE PLUMBING
J 2
(-2850 2500);
DISPLAY 1.595745 (-2850 2500);
PAINT GREEN (-2850 2500);
DISPLAY INVISIBLE (-2850 2500);
FORCEPROP 1 LAST HDL_TAP TRUE
J 2
(-3175 2425);
DISPLAY 1.595745 (-3175 2425);
PAINT GREEN (-3175 2425);
DISPLAY INVISIBLE (-3175 2425);
FORCEPROP 1 LAST PATH I119
J 2
(-2848 2550);
DISPLAY 0.872340 (-2848 2550);
PAINT GREEN (-2848 2550);
DISPLAY INVISIBLE (-2848 2550);
FORCEADD TAP..6
(-5575 1000);
FORCEPROP 3 LASTPIN (-5525 1000) SIG_NAME M_C_CLK_DP<3>
J 0
(-5515 1010);
DISPLAY 0.659574 (-5515 1010);
PAINT MONO (-5515 1010);
DISPLAY INVISIBLE (-5515 1010);
FORCEPROP 1 LASTPIN (-5525 1000) BN 3
J 0
(-5577 1008);
DISPLAY 0.617021 (-5577 1008);
PAINT PINK (-5577 1008);
FORCEPROP 2 LAST CDS_LIB mstr_standard
J 0
(-5575 1000);
PAINT MONO (-5575 1000);
DISPLAY INVISIBLE (-5575 1000);
FORCEPROP 1 LAST BODY_TYPE PLUMBING
J 0
(-5575 950);
DISPLAY 1.595745 (-5575 950);
PAINT GREEN (-5575 950);
DISPLAY INVISIBLE (-5575 950);
FORCEPROP 1 LAST HDL_TAP TRUE
J 0
(-5250 875);
DISPLAY 1.595745 (-5250 875);
PAINT GREEN (-5250 875);
DISPLAY INVISIBLE (-5250 875);
FORCEPROP 1 LAST PATH I12
J 0
(-5577 1000);
DISPLAY 0.872340 (-5577 1000);
PAINT GREEN (-5577 1000);
DISPLAY INVISIBLE (-5577 1000);
FORCEADD TAP..6
R 2
(-2850 2600);
FORCEPROP 3 LASTPIN (-2900 2600) SIG_NAME M_C_MA<13>
J 0
(-2890 2610);
DISPLAY 0.659574 (-2890 2610);
PAINT MONO (-2890 2610);
DISPLAY INVISIBLE (-2890 2610);
FORCEPROP 1 LASTPIN (-2900 2600) BN 13
J 2
(-2848 2608);
DISPLAY 0.617021 (-2848 2608);
PAINT PINK (-2848 2608);
FORCEPROP 2 LAST CDS_LIB mstr_standard
J 0
(-2850 2600);
PAINT MONO (-2850 2600);
DISPLAY INVISIBLE (-2850 2600);
FORCEPROP 1 LAST BODY_TYPE PLUMBING
J 2
(-2850 2550);
DISPLAY 1.595745 (-2850 2550);
PAINT GREEN (-2850 2550);
DISPLAY INVISIBLE (-2850 2550);
FORCEPROP 1 LAST HDL_TAP TRUE
J 2
(-3175 2475);
DISPLAY 1.595745 (-3175 2475);
PAINT GREEN (-3175 2475);
DISPLAY INVISIBLE (-3175 2475);
FORCEPROP 1 LAST PATH I120
J 2
(-2848 2600);
DISPLAY 0.872340 (-2848 2600);
PAINT GREEN (-2848 2600);
DISPLAY INVISIBLE (-2848 2600);
FORCEADD TAP..6
R 2
(-2850 2650);
FORCEPROP 3 LASTPIN (-2900 2650) SIG_NAME M_C_MA<14>
J 0
(-2890 2660);
DISPLAY 0.659574 (-2890 2660);
PAINT MONO (-2890 2660);
DISPLAY INVISIBLE (-2890 2660);
FORCEPROP 1 LASTPIN (-2900 2650) BN 14
J 2
(-2848 2658);
DISPLAY 0.617021 (-2848 2658);
PAINT PINK (-2848 2658);
FORCEPROP 2 LAST CDS_LIB mstr_standard
J 0
(-2850 2650);
PAINT MONO (-2850 2650);
DISPLAY INVISIBLE (-2850 2650);
FORCEPROP 1 LAST BODY_TYPE PLUMBING
J 2
(-2850 2600);
DISPLAY 1.595745 (-2850 2600);
PAINT GREEN (-2850 2600);
DISPLAY INVISIBLE (-2850 2600);
FORCEPROP 1 LAST HDL_TAP TRUE
J 2
(-3175 2525);
DISPLAY 1.595745 (-3175 2525);
PAINT GREEN (-3175 2525);
DISPLAY INVISIBLE (-3175 2525);
FORCEPROP 1 LAST PATH I121
J 2
(-2848 2650);
DISPLAY 0.872340 (-2848 2650);
PAINT GREEN (-2848 2650);
DISPLAY INVISIBLE (-2848 2650);
FORCEADD TAP..6
R 2
(-2850 2700);
FORCEPROP 3 LASTPIN (-2900 2700) SIG_NAME M_C_MA<15>
J 0
(-2890 2710);
DISPLAY 0.659574 (-2890 2710);
PAINT MONO (-2890 2710);
DISPLAY INVISIBLE (-2890 2710);
FORCEPROP 1 LASTPIN (-2900 2700) BN 15
J 2
(-2848 2708);
DISPLAY 0.617021 (-2848 2708);
PAINT PINK (-2848 2708);
FORCEPROP 2 LAST CDS_LIB mstr_standard
J 0
(-2850 2700);
PAINT MONO (-2850 2700);
DISPLAY INVISIBLE (-2850 2700);
FORCEPROP 1 LAST BODY_TYPE PLUMBING
J 2
(-2850 2650);
DISPLAY 1.595745 (-2850 2650);
PAINT GREEN (-2850 2650);
DISPLAY INVISIBLE (-2850 2650);
FORCEPROP 1 LAST HDL_TAP TRUE
J 2
(-3175 2575);
DISPLAY 1.595745 (-3175 2575);
PAINT GREEN (-3175 2575);
DISPLAY INVISIBLE (-3175 2575);
FORCEPROP 1 LAST PATH I122
J 2
(-2848 2700);
DISPLAY 0.872340 (-2848 2700);
PAINT GREEN (-2848 2700);
DISPLAY INVISIBLE (-2848 2700);
FORCEADD TAP..6
R 2
(-2850 2750);
FORCEPROP 3 LASTPIN (-2900 2750) SIG_NAME M_C_MA<16>
J 0
(-2890 2760);
DISPLAY 0.659574 (-2890 2760);
PAINT MONO (-2890 2760);
DISPLAY INVISIBLE (-2890 2760);
FORCEPROP 1 LASTPIN (-2900 2750) BN 16
J 2
(-2848 2758);
DISPLAY 0.617021 (-2848 2758);
PAINT PINK (-2848 2758);
FORCEPROP 2 LAST CDS_LIB mstr_standard
J 0
(-2850 2750);
PAINT MONO (-2850 2750);
DISPLAY INVISIBLE (-2850 2750);
FORCEPROP 1 LAST BODY_TYPE PLUMBING
J 2
(-2850 2700);
DISPLAY 1.595745 (-2850 2700);
PAINT GREEN (-2850 2700);
DISPLAY INVISIBLE (-2850 2700);
FORCEPROP 1 LAST HDL_TAP TRUE
J 2
(-3175 2625);
DISPLAY 1.595745 (-3175 2625);
PAINT GREEN (-3175 2625);
DISPLAY INVISIBLE (-3175 2625);
FORCEPROP 1 LAST PATH I123
J 2
(-2848 2750);
DISPLAY 0.872340 (-2848 2750);
PAINT GREEN (-2848 2750);
DISPLAY INVISIBLE (-2848 2750);
FORCEADD TAP..6
R 2
(-2850 2800);
FORCEPROP 3 LASTPIN (-2900 2800) SIG_NAME M_C_MA<17>
J 0
(-2890 2810);
DISPLAY 0.659574 (-2890 2810);
PAINT MONO (-2890 2810);
DISPLAY INVISIBLE (-2890 2810);
FORCEPROP 1 LASTPIN (-2900 2800) BN 17
J 2
(-2848 2808);
DISPLAY 0.617021 (-2848 2808);
PAINT PINK (-2848 2808);
FORCEPROP 2 LAST CDS_LIB mstr_standard
J 0
(-2850 2800);
PAINT MONO (-2850 2800);
DISPLAY INVISIBLE (-2850 2800);
FORCEPROP 1 LAST BODY_TYPE PLUMBING
J 2
(-2850 2750);
DISPLAY 1.595745 (-2850 2750);
PAINT GREEN (-2850 2750);
DISPLAY INVISIBLE (-2850 2750);
FORCEPROP 1 LAST HDL_TAP TRUE
J 2
(-3175 2675);
DISPLAY 1.595745 (-3175 2675);
PAINT GREEN (-3175 2675);
DISPLAY INVISIBLE (-3175 2675);
FORCEPROP 1 LAST PATH I124
J 2
(-2848 2800);
DISPLAY 0.872340 (-2848 2800);
PAINT GREEN (-2848 2800);
DISPLAY INVISIBLE (-2848 2800);
FORCEADD TAP..6
R 2
(-2850 2950);
FORCEPROP 3 LASTPIN (-2900 2950) SIG_NAME M_C_DQS_DN<1>
J 0
(-2890 2960);
DISPLAY 0.659574 (-2890 2960);
PAINT MONO (-2890 2960);
DISPLAY INVISIBLE (-2890 2960);
FORCEPROP 1 LASTPIN (-2900 2950) BN 1
J 2
(-2848 2958);
DISPLAY 0.617021 (-2848 2958);
PAINT PINK (-2848 2958);
FORCEPROP 2 LAST CDS_LIB mstr_standard
J 0
(-2850 2950);
PAINT MONO (-2850 2950);
DISPLAY INVISIBLE (-2850 2950);
FORCEPROP 1 LAST BODY_TYPE PLUMBING
J 2
(-2850 2900);
DISPLAY 1.595745 (-2850 2900);
PAINT GREEN (-2850 2900);
DISPLAY INVISIBLE (-2850 2900);
FORCEPROP 1 LAST HDL_TAP TRUE
J 2
(-3175 2825);
DISPLAY 1.595745 (-3175 2825);
PAINT GREEN (-3175 2825);
DISPLAY INVISIBLE (-3175 2825);
FORCEPROP 1 LAST PATH I125
J 2
(-2848 2950);
DISPLAY 0.872340 (-2848 2950);
PAINT GREEN (-2848 2950);
DISPLAY INVISIBLE (-2848 2950);
FORCEADD TAP..6
R 2
(-2850 2900);
FORCEPROP 3 LASTPIN (-2900 2900) SIG_NAME M_C_DQS_DN<0>
J 0
(-2890 2910);
DISPLAY 0.659574 (-2890 2910);
PAINT MONO (-2890 2910);
DISPLAY INVISIBLE (-2890 2910);
FORCEPROP 1 LASTPIN (-2900 2900) BN 0
J 2
(-2848 2908);
DISPLAY 0.617021 (-2848 2908);
PAINT PINK (-2848 2908);
FORCEPROP 2 LAST CDS_LIB mstr_standard
J 0
(-2850 2900);
PAINT MONO (-2850 2900);
DISPLAY INVISIBLE (-2850 2900);
FORCEPROP 1 LAST BODY_TYPE PLUMBING
J 2
(-2850 2850);
DISPLAY 1.595745 (-2850 2850);
PAINT GREEN (-2850 2850);
DISPLAY INVISIBLE (-2850 2850);
FORCEPROP 1 LAST HDL_TAP TRUE
J 2
(-3175 2775);
DISPLAY 1.595745 (-3175 2775);
PAINT GREEN (-3175 2775);
DISPLAY INVISIBLE (-3175 2775);
FORCEPROP 1 LAST PATH I126
J 2
(-2848 2900);
DISPLAY 0.872340 (-2848 2900);
PAINT GREEN (-2848 2900);
DISPLAY INVISIBLE (-2848 2900);
FORCEADD TAP..6
R 2
(-2850 3000);
FORCEPROP 3 LASTPIN (-2900 3000) SIG_NAME M_C_DQS_DN<2>
J 0
(-2890 3010);
DISPLAY 0.659574 (-2890 3010);
PAINT MONO (-2890 3010);
DISPLAY INVISIBLE (-2890 3010);
FORCEPROP 1 LASTPIN (-2900 3000) BN 2
J 2
(-2848 3008);
DISPLAY 0.617021 (-2848 3008);
PAINT PINK (-2848 3008);
FORCEPROP 2 LAST CDS_LIB mstr_standard
J 0
(-2850 3000);
PAINT MONO (-2850 3000);
DISPLAY INVISIBLE (-2850 3000);
FORCEPROP 1 LAST BODY_TYPE PLUMBING
J 2
(-2850 2950);
DISPLAY 1.595745 (-2850 2950);
PAINT GREEN (-2850 2950);
DISPLAY INVISIBLE (-2850 2950);
FORCEPROP 1 LAST HDL_TAP TRUE
J 2
(-3175 2875);
DISPLAY 1.595745 (-3175 2875);
PAINT GREEN (-3175 2875);
DISPLAY INVISIBLE (-3175 2875);
FORCEPROP 1 LAST PATH I127
J 2
(-2848 3000);
DISPLAY 0.872340 (-2848 3000);
PAINT GREEN (-2848 3000);
DISPLAY INVISIBLE (-2848 3000);
FORCEADD TAP..6
R 2
(-2850 3050);
FORCEPROP 3 LASTPIN (-2900 3050) SIG_NAME M_C_DQS_DN<3>
J 0
(-2890 3060);
DISPLAY 0.659574 (-2890 3060);
PAINT MONO (-2890 3060);
DISPLAY INVISIBLE (-2890 3060);
FORCEPROP 1 LASTPIN (-2900 3050) BN 3
J 2
(-2848 3058);
DISPLAY 0.617021 (-2848 3058);
PAINT PINK (-2848 3058);
FORCEPROP 2 LAST CDS_LIB mstr_standard
J 0
(-2850 3050);
PAINT MONO (-2850 3050);
DISPLAY INVISIBLE (-2850 3050);
FORCEPROP 1 LAST BODY_TYPE PLUMBING
J 2
(-2850 3000);
DISPLAY 1.595745 (-2850 3000);
PAINT GREEN (-2850 3000);
DISPLAY INVISIBLE (-2850 3000);
FORCEPROP 1 LAST HDL_TAP TRUE
J 2
(-3175 2925);
DISPLAY 1.595745 (-3175 2925);
PAINT GREEN (-3175 2925);
DISPLAY INVISIBLE (-3175 2925);
FORCEPROP 1 LAST PATH I128
J 2
(-2848 3050);
DISPLAY 0.872340 (-2848 3050);
PAINT GREEN (-2848 3050);
DISPLAY INVISIBLE (-2848 3050);
FORCEADD TAP..6
R 2
(-2850 3100);
FORCEPROP 3 LASTPIN (-2900 3100) SIG_NAME M_C_DQS_DN<4>
J 0
(-2890 3110);
DISPLAY 0.659574 (-2890 3110);
PAINT MONO (-2890 3110);
DISPLAY INVISIBLE (-2890 3110);
FORCEPROP 1 LASTPIN (-2900 3100) BN 4
J 2
(-2848 3108);
DISPLAY 0.617021 (-2848 3108);
PAINT PINK (-2848 3108);
FORCEPROP 2 LAST CDS_LIB mstr_standard
J 0
(-2850 3100);
PAINT MONO (-2850 3100);
DISPLAY INVISIBLE (-2850 3100);
FORCEPROP 1 LAST BODY_TYPE PLUMBING
J 2
(-2850 3050);
DISPLAY 1.595745 (-2850 3050);
PAINT GREEN (-2850 3050);
DISPLAY INVISIBLE (-2850 3050);
FORCEPROP 1 LAST HDL_TAP TRUE
J 2
(-3175 2975);
DISPLAY 1.595745 (-3175 2975);
PAINT GREEN (-3175 2975);
DISPLAY INVISIBLE (-3175 2975);
FORCEPROP 1 LAST PATH I129
J 2
(-2848 3100);
DISPLAY 0.872340 (-2848 3100);
PAINT GREEN (-2848 3100);
DISPLAY INVISIBLE (-2848 3100);
FORCEADD TAP..6
(-5575 1100);
FORCEPROP 3 LASTPIN (-5525 1100) SIG_NAME M_C_ECC<0>
J 0
(-5515 1110);
DISPLAY 0.659574 (-5515 1110);
PAINT MONO (-5515 1110);
DISPLAY INVISIBLE (-5515 1110);
FORCEPROP 1 LASTPIN (-5525 1100) BN 0
J 0
(-5577 1108);
DISPLAY 0.617021 (-5577 1108);
PAINT PINK (-5577 1108);
FORCEPROP 2 LAST CDS_LIB mstr_standard
J 0
(-5575 1100);
PAINT MONO (-5575 1100);
DISPLAY INVISIBLE (-5575 1100);
FORCEPROP 1 LAST BODY_TYPE PLUMBING
J 0
(-5575 1050);
DISPLAY 1.595745 (-5575 1050);
PAINT GREEN (-5575 1050);
DISPLAY INVISIBLE (-5575 1050);
FORCEPROP 1 LAST HDL_TAP TRUE
J 0
(-5250 975);
DISPLAY 1.595745 (-5250 975);
PAINT GREEN (-5250 975);
DISPLAY INVISIBLE (-5250 975);
FORCEPROP 1 LAST PATH I13
J 0
(-5577 1100);
DISPLAY 0.872340 (-5577 1100);
PAINT GREEN (-5577 1100);
DISPLAY INVISIBLE (-5577 1100);
FORCEADD TAP..6
R 2
(-2850 3150);
FORCEPROP 3 LASTPIN (-2900 3150) SIG_NAME M_C_DQS_DN<5>
J 0
(-2890 3160);
DISPLAY 0.659574 (-2890 3160);
PAINT MONO (-2890 3160);
DISPLAY INVISIBLE (-2890 3160);
FORCEPROP 1 LASTPIN (-2900 3150) BN 5
J 2
(-2848 3158);
DISPLAY 0.617021 (-2848 3158);
PAINT PINK (-2848 3158);
FORCEPROP 2 LAST CDS_LIB mstr_standard
J 0
(-2850 3150);
PAINT MONO (-2850 3150);
DISPLAY INVISIBLE (-2850 3150);
FORCEPROP 1 LAST BODY_TYPE PLUMBING
J 2
(-2850 3100);
DISPLAY 1.595745 (-2850 3100);
PAINT GREEN (-2850 3100);
DISPLAY INVISIBLE (-2850 3100);
FORCEPROP 1 LAST HDL_TAP TRUE
J 2
(-3175 3025);
DISPLAY 1.595745 (-3175 3025);
PAINT GREEN (-3175 3025);
DISPLAY INVISIBLE (-3175 3025);
FORCEPROP 1 LAST PATH I130
J 2
(-2848 3150);
DISPLAY 0.872340 (-2848 3150);
PAINT GREEN (-2848 3150);
DISPLAY INVISIBLE (-2848 3150);
FORCEADD TAP..6
R 2
(-2850 3250);
FORCEPROP 3 LASTPIN (-2900 3250) SIG_NAME M_C_DQS_DN<7>
J 0
(-2890 3260);
DISPLAY 0.659574 (-2890 3260);
PAINT MONO (-2890 3260);
DISPLAY INVISIBLE (-2890 3260);
FORCEPROP 1 LASTPIN (-2900 3250) BN 7
J 2
(-2848 3258);
DISPLAY 0.617021 (-2848 3258);
PAINT PINK (-2848 3258);
FORCEPROP 2 LAST CDS_LIB mstr_standard
J 0
(-2850 3250);
PAINT MONO (-2850 3250);
DISPLAY INVISIBLE (-2850 3250);
FORCEPROP 1 LAST BODY_TYPE PLUMBING
J 2
(-2850 3200);
DISPLAY 1.595745 (-2850 3200);
PAINT GREEN (-2850 3200);
DISPLAY INVISIBLE (-2850 3200);
FORCEPROP 1 LAST HDL_TAP TRUE
J 2
(-3175 3125);
DISPLAY 1.595745 (-3175 3125);
PAINT GREEN (-3175 3125);
DISPLAY INVISIBLE (-3175 3125);
FORCEPROP 1 LAST PATH I131
J 2
(-2848 3250);
DISPLAY 0.872340 (-2848 3250);
PAINT GREEN (-2848 3250);
DISPLAY INVISIBLE (-2848 3250);
FORCEADD TAP..6
R 2
(-2850 3200);
FORCEPROP 3 LASTPIN (-2900 3200) SIG_NAME M_C_DQS_DN<6>
J 0
(-2890 3210);
DISPLAY 0.659574 (-2890 3210);
PAINT MONO (-2890 3210);
DISPLAY INVISIBLE (-2890 3210);
FORCEPROP 1 LASTPIN (-2900 3200) BN 6
J 2
(-2848 3208);
DISPLAY 0.617021 (-2848 3208);
PAINT PINK (-2848 3208);
FORCEPROP 2 LAST CDS_LIB mstr_standard
J 0
(-2850 3200);
PAINT MONO (-2850 3200);
DISPLAY INVISIBLE (-2850 3200);
FORCEPROP 1 LAST BODY_TYPE PLUMBING
J 2
(-2850 3150);
DISPLAY 1.595745 (-2850 3150);
PAINT GREEN (-2850 3150);
DISPLAY INVISIBLE (-2850 3150);
FORCEPROP 1 LAST HDL_TAP TRUE
J 2
(-3175 3075);
DISPLAY 1.595745 (-3175 3075);
PAINT GREEN (-3175 3075);
DISPLAY INVISIBLE (-3175 3075);
FORCEPROP 1 LAST PATH I132
J 2
(-2848 3200);
DISPLAY 0.872340 (-2848 3200);
PAINT GREEN (-2848 3200);
DISPLAY INVISIBLE (-2848 3200);
FORCEADD TAP..6
R 2
(-2850 3300);
FORCEPROP 3 LASTPIN (-2900 3300) SIG_NAME M_C_DQS_DN<8>
J 0
(-2890 3310);
DISPLAY 0.659574 (-2890 3310);
PAINT MONO (-2890 3310);
DISPLAY INVISIBLE (-2890 3310);
FORCEPROP 1 LASTPIN (-2900 3300) BN 8
J 2
(-2848 3308);
DISPLAY 0.617021 (-2848 3308);
PAINT PINK (-2848 3308);
FORCEPROP 2 LAST CDS_LIB mstr_standard
J 0
(-2850 3300);
PAINT MONO (-2850 3300);
DISPLAY INVISIBLE (-2850 3300);
FORCEPROP 1 LAST BODY_TYPE PLUMBING
J 2
(-2850 3250);
DISPLAY 1.595745 (-2850 3250);
PAINT GREEN (-2850 3250);
DISPLAY INVISIBLE (-2850 3250);
FORCEPROP 1 LAST HDL_TAP TRUE
J 2
(-3175 3175);
DISPLAY 1.595745 (-3175 3175);
PAINT GREEN (-3175 3175);
DISPLAY INVISIBLE (-3175 3175);
FORCEPROP 1 LAST PATH I133
J 2
(-2848 3300);
DISPLAY 0.872340 (-2848 3300);
PAINT GREEN (-2848 3300);
DISPLAY INVISIBLE (-2848 3300);
FORCEADD TAP..6
R 2
(-2850 3350);
FORCEPROP 3 LASTPIN (-2900 3350) SIG_NAME M_C_DQS_DN<9>
J 0
(-2890 3360);
DISPLAY 0.659574 (-2890 3360);
PAINT MONO (-2890 3360);
DISPLAY INVISIBLE (-2890 3360);
FORCEPROP 1 LASTPIN (-2900 3350) BN 9
J 2
(-2848 3358);
DISPLAY 0.617021 (-2848 3358);
PAINT PINK (-2848 3358);
FORCEPROP 2 LAST CDS_LIB mstr_standard
J 0
(-2850 3350);
PAINT MONO (-2850 3350);
DISPLAY INVISIBLE (-2850 3350);
FORCEPROP 1 LAST BODY_TYPE PLUMBING
J 2
(-2850 3300);
DISPLAY 1.595745 (-2850 3300);
PAINT GREEN (-2850 3300);
DISPLAY INVISIBLE (-2850 3300);
FORCEPROP 1 LAST HDL_TAP TRUE
J 2
(-3175 3225);
DISPLAY 1.595745 (-3175 3225);
PAINT GREEN (-3175 3225);
DISPLAY INVISIBLE (-3175 3225);
FORCEPROP 1 LAST PATH I134
J 2
(-2848 3350);
DISPLAY 0.872340 (-2848 3350);
PAINT GREEN (-2848 3350);
DISPLAY INVISIBLE (-2848 3350);
FORCEADD TAP..6
R 2
(-2850 3400);
FORCEPROP 3 LASTPIN (-2900 3400) SIG_NAME M_C_DQS_DN<10>
J 0
(-2890 3410);
DISPLAY 0.659574 (-2890 3410);
PAINT MONO (-2890 3410);
DISPLAY INVISIBLE (-2890 3410);
FORCEPROP 1 LASTPIN (-2900 3400) BN 10
J 2
(-2848 3408);
DISPLAY 0.617021 (-2848 3408);
PAINT PINK (-2848 3408);
FORCEPROP 2 LAST CDS_LIB mstr_standard
J 0
(-2850 3400);
PAINT MONO (-2850 3400);
DISPLAY INVISIBLE (-2850 3400);
FORCEPROP 1 LAST BODY_TYPE PLUMBING
J 2
(-2850 3350);
DISPLAY 1.595745 (-2850 3350);
PAINT GREEN (-2850 3350);
DISPLAY INVISIBLE (-2850 3350);
FORCEPROP 1 LAST HDL_TAP TRUE
J 2
(-3175 3275);
DISPLAY 1.595745 (-3175 3275);
PAINT GREEN (-3175 3275);
DISPLAY INVISIBLE (-3175 3275);
FORCEPROP 1 LAST PATH I135
J 2
(-2848 3400);
DISPLAY 0.872340 (-2848 3400);
PAINT GREEN (-2848 3400);
DISPLAY INVISIBLE (-2848 3400);
FORCEADD TAP..6
R 2
(-2850 3500);
FORCEPROP 3 LASTPIN (-2900 3500) SIG_NAME M_C_DQS_DN<12>
J 0
(-2890 3510);
DISPLAY 0.659574 (-2890 3510);
PAINT MONO (-2890 3510);
DISPLAY INVISIBLE (-2890 3510);
FORCEPROP 1 LASTPIN (-2900 3500) BN 12
J 2
(-2848 3508);
DISPLAY 0.617021 (-2848 3508);
PAINT PINK (-2848 3508);
FORCEPROP 2 LAST CDS_LIB mstr_standard
J 0
(-2850 3500);
PAINT MONO (-2850 3500);
DISPLAY INVISIBLE (-2850 3500);
FORCEPROP 1 LAST BODY_TYPE PLUMBING
J 2
(-2850 3450);
DISPLAY 1.595745 (-2850 3450);
PAINT GREEN (-2850 3450);
DISPLAY INVISIBLE (-2850 3450);
FORCEPROP 1 LAST HDL_TAP TRUE
J 2
(-3175 3375);
DISPLAY 1.595745 (-3175 3375);
PAINT GREEN (-3175 3375);
DISPLAY INVISIBLE (-3175 3375);
FORCEPROP 1 LAST PATH I136
J 2
(-2848 3500);
DISPLAY 0.872340 (-2848 3500);
PAINT GREEN (-2848 3500);
DISPLAY INVISIBLE (-2848 3500);
FORCEADD TAP..6
R 2
(-2850 3450);
FORCEPROP 3 LASTPIN (-2900 3450) SIG_NAME M_C_DQS_DN<11>
J 0
(-2890 3460);
DISPLAY 0.659574 (-2890 3460);
PAINT MONO (-2890 3460);
DISPLAY INVISIBLE (-2890 3460);
FORCEPROP 1 LASTPIN (-2900 3450) BN 11
J 2
(-2848 3458);
DISPLAY 0.617021 (-2848 3458);
PAINT PINK (-2848 3458);
FORCEPROP 2 LAST CDS_LIB mstr_standard
J 0
(-2850 3450);
PAINT MONO (-2850 3450);
DISPLAY INVISIBLE (-2850 3450);
FORCEPROP 1 LAST BODY_TYPE PLUMBING
J 2
(-2850 3400);
DISPLAY 1.595745 (-2850 3400);
PAINT GREEN (-2850 3400);
DISPLAY INVISIBLE (-2850 3400);
FORCEPROP 1 LAST HDL_TAP TRUE
J 2
(-3175 3325);
DISPLAY 1.595745 (-3175 3325);
PAINT GREEN (-3175 3325);
DISPLAY INVISIBLE (-3175 3325);
FORCEPROP 1 LAST PATH I137
J 2
(-2848 3450);
DISPLAY 0.872340 (-2848 3450);
PAINT GREEN (-2848 3450);
DISPLAY INVISIBLE (-2848 3450);
FORCEADD TAP..6
R 2
(-2850 3550);
FORCEPROP 3 LASTPIN (-2900 3550) SIG_NAME M_C_DQS_DN<13>
J 0
(-2890 3560);
DISPLAY 0.659574 (-2890 3560);
PAINT MONO (-2890 3560);
DISPLAY INVISIBLE (-2890 3560);
FORCEPROP 1 LASTPIN (-2900 3550) BN 13
J 2
(-2848 3558);
DISPLAY 0.617021 (-2848 3558);
PAINT PINK (-2848 3558);
FORCEPROP 2 LAST CDS_LIB mstr_standard
J 0
(-2850 3550);
PAINT MONO (-2850 3550);
DISPLAY INVISIBLE (-2850 3550);
FORCEPROP 1 LAST BODY_TYPE PLUMBING
J 2
(-2850 3500);
DISPLAY 1.595745 (-2850 3500);
PAINT GREEN (-2850 3500);
DISPLAY INVISIBLE (-2850 3500);
FORCEPROP 1 LAST HDL_TAP TRUE
J 2
(-3175 3425);
DISPLAY 1.595745 (-3175 3425);
PAINT GREEN (-3175 3425);
DISPLAY INVISIBLE (-3175 3425);
FORCEPROP 1 LAST PATH I138
J 2
(-2848 3550);
DISPLAY 0.872340 (-2848 3550);
PAINT GREEN (-2848 3550);
DISPLAY INVISIBLE (-2848 3550);
FORCEADD TAP..6
R 2
(-2850 3650);
FORCEPROP 3 LASTPIN (-2900 3650) SIG_NAME M_C_DQS_DN<15>
J 0
(-2890 3660);
DISPLAY 0.659574 (-2890 3660);
PAINT MONO (-2890 3660);
DISPLAY INVISIBLE (-2890 3660);
FORCEPROP 1 LASTPIN (-2900 3650) BN 15
J 2
(-2848 3658);
DISPLAY 0.617021 (-2848 3658);
PAINT PINK (-2848 3658);
FORCEPROP 2 LAST CDS_LIB mstr_standard
J 0
(-2850 3650);
PAINT MONO (-2850 3650);
DISPLAY INVISIBLE (-2850 3650);
FORCEPROP 1 LAST BODY_TYPE PLUMBING
J 2
(-2850 3600);
DISPLAY 1.595745 (-2850 3600);
PAINT GREEN (-2850 3600);
DISPLAY INVISIBLE (-2850 3600);
FORCEPROP 1 LAST HDL_TAP TRUE
J 2
(-3175 3525);
DISPLAY 1.595745 (-3175 3525);
PAINT GREEN (-3175 3525);
DISPLAY INVISIBLE (-3175 3525);
FORCEPROP 1 LAST PATH I139
J 2
(-2848 3650);
DISPLAY 0.872340 (-2848 3650);
PAINT GREEN (-2848 3650);
DISPLAY INVISIBLE (-2848 3650);
FORCEADD TAP..6
(-5575 1150);
FORCEPROP 3 LASTPIN (-5525 1150) SIG_NAME M_C_ECC<1>
J 0
(-5515 1160);
DISPLAY 0.659574 (-5515 1160);
PAINT MONO (-5515 1160);
DISPLAY INVISIBLE (-5515 1160);
FORCEPROP 1 LASTPIN (-5525 1150) BN 1
J 0
(-5577 1158);
DISPLAY 0.617021 (-5577 1158);
PAINT PINK (-5577 1158);
FORCEPROP 2 LAST CDS_LIB mstr_standard
J 0
(-5575 1150);
PAINT MONO (-5575 1150);
DISPLAY INVISIBLE (-5575 1150);
FORCEPROP 1 LAST BODY_TYPE PLUMBING
J 0
(-5575 1100);
DISPLAY 1.595745 (-5575 1100);
PAINT GREEN (-5575 1100);
DISPLAY INVISIBLE (-5575 1100);
FORCEPROP 1 LAST HDL_TAP TRUE
J 0
(-5250 1025);
DISPLAY 1.595745 (-5250 1025);
PAINT GREEN (-5250 1025);
DISPLAY INVISIBLE (-5250 1025);
FORCEPROP 1 LAST PATH I14
J 0
(-5577 1150);
DISPLAY 0.872340 (-5577 1150);
PAINT GREEN (-5577 1150);
DISPLAY INVISIBLE (-5577 1150);
FORCEADD TAP..6
R 2
(-2850 3600);
FORCEPROP 3 LASTPIN (-2900 3600) SIG_NAME M_C_DQS_DN<14>
J 0
(-2890 3610);
DISPLAY 0.659574 (-2890 3610);
PAINT MONO (-2890 3610);
DISPLAY INVISIBLE (-2890 3610);
FORCEPROP 1 LASTPIN (-2900 3600) BN 14
J 2
(-2848 3608);
DISPLAY 0.617021 (-2848 3608);
PAINT PINK (-2848 3608);
FORCEPROP 2 LAST CDS_LIB mstr_standard
J 0
(-2850 3600);
PAINT MONO (-2850 3600);
DISPLAY INVISIBLE (-2850 3600);
FORCEPROP 1 LAST BODY_TYPE PLUMBING
J 2
(-2850 3550);
DISPLAY 1.595745 (-2850 3550);
PAINT GREEN (-2850 3550);
DISPLAY INVISIBLE (-2850 3550);
FORCEPROP 1 LAST HDL_TAP TRUE
J 2
(-3175 3475);
DISPLAY 1.595745 (-3175 3475);
PAINT GREEN (-3175 3475);
DISPLAY INVISIBLE (-3175 3475);
FORCEPROP 1 LAST PATH I140
J 2
(-2848 3600);
DISPLAY 0.872340 (-2848 3600);
PAINT GREEN (-2848 3600);
DISPLAY INVISIBLE (-2848 3600);
FORCEADD TAP..6
R 2
(-2850 3750);
FORCEPROP 3 LASTPIN (-2900 3750) SIG_NAME M_C_DQS_DN<17>
J 0
(-2890 3760);
DISPLAY 0.659574 (-2890 3760);
PAINT MONO (-2890 3760);
DISPLAY INVISIBLE (-2890 3760);
FORCEPROP 1 LASTPIN (-2900 3750) BN 17
J 2
(-2848 3758);
DISPLAY 0.617021 (-2848 3758);
PAINT PINK (-2848 3758);
FORCEPROP 2 LAST CDS_LIB mstr_standard
J 0
(-2850 3750);
PAINT MONO (-2850 3750);
DISPLAY INVISIBLE (-2850 3750);
FORCEPROP 1 LAST BODY_TYPE PLUMBING
J 2
(-2850 3700);
DISPLAY 1.595745 (-2850 3700);
PAINT GREEN (-2850 3700);
DISPLAY INVISIBLE (-2850 3700);
FORCEPROP 1 LAST HDL_TAP TRUE
J 2
(-3175 3625);
DISPLAY 1.595745 (-3175 3625);
PAINT GREEN (-3175 3625);
DISPLAY INVISIBLE (-3175 3625);
FORCEPROP 1 LAST PATH I141
J 2
(-2848 3750);
DISPLAY 0.872340 (-2848 3750);
PAINT GREEN (-2848 3750);
DISPLAY INVISIBLE (-2848 3750);
FORCEADD TAP..6
R 2
(-2850 3700);
FORCEPROP 3 LASTPIN (-2900 3700) SIG_NAME M_C_DQS_DN<16>
J 0
(-2890 3710);
DISPLAY 0.659574 (-2890 3710);
PAINT MONO (-2890 3710);
DISPLAY INVISIBLE (-2890 3710);
FORCEPROP 1 LASTPIN (-2900 3700) BN 16
J 2
(-2848 3708);
DISPLAY 0.617021 (-2848 3708);
PAINT PINK (-2848 3708);
FORCEPROP 2 LAST CDS_LIB mstr_standard
J 0
(-2850 3700);
PAINT MONO (-2850 3700);
DISPLAY INVISIBLE (-2850 3700);
FORCEPROP 1 LAST BODY_TYPE PLUMBING
J 2
(-2850 3650);
DISPLAY 1.595745 (-2850 3650);
PAINT GREEN (-2850 3650);
DISPLAY INVISIBLE (-2850 3650);
FORCEPROP 1 LAST HDL_TAP TRUE
J 2
(-3175 3575);
DISPLAY 1.595745 (-3175 3575);
PAINT GREEN (-3175 3575);
DISPLAY INVISIBLE (-3175 3575);
FORCEPROP 1 LAST PATH I142
J 2
(-2848 3700);
DISPLAY 0.872340 (-2848 3700);
PAINT GREEN (-2848 3700);
DISPLAY INVISIBLE (-2848 3700);
FORCEADD TAP..6
R 2
(-2850 3900);
FORCEPROP 3 LASTPIN (-2900 3900) SIG_NAME M_C_DQS_DP<1>
J 0
(-2890 3910);
DISPLAY 0.659574 (-2890 3910);
PAINT MONO (-2890 3910);
DISPLAY INVISIBLE (-2890 3910);
FORCEPROP 1 LASTPIN (-2900 3900) BN 1
J 2
(-2848 3908);
DISPLAY 0.617021 (-2848 3908);
PAINT PINK (-2848 3908);
FORCEPROP 2 LAST CDS_LIB mstr_standard
J 0
(-2850 3900);
PAINT MONO (-2850 3900);
DISPLAY INVISIBLE (-2850 3900);
FORCEPROP 1 LAST BODY_TYPE PLUMBING
J 2
(-2850 3850);
DISPLAY 1.595745 (-2850 3850);
PAINT GREEN (-2850 3850);
DISPLAY INVISIBLE (-2850 3850);
FORCEPROP 1 LAST HDL_TAP TRUE
J 2
(-3175 3775);
DISPLAY 1.595745 (-3175 3775);
PAINT GREEN (-3175 3775);
DISPLAY INVISIBLE (-3175 3775);
FORCEPROP 1 LAST PATH I143
J 2
(-2848 3900);
DISPLAY 0.872340 (-2848 3900);
PAINT GREEN (-2848 3900);
DISPLAY INVISIBLE (-2848 3900);
FORCEADD TAP..6
R 2
(-2850 3850);
FORCEPROP 3 LASTPIN (-2900 3850) SIG_NAME M_C_DQS_DP<0>
J 0
(-2890 3860);
DISPLAY 0.659574 (-2890 3860);
PAINT MONO (-2890 3860);
DISPLAY INVISIBLE (-2890 3860);
FORCEPROP 1 LASTPIN (-2900 3850) BN 0
J 2
(-2848 3858);
DISPLAY 0.617021 (-2848 3858);
PAINT PINK (-2848 3858);
FORCEPROP 2 LAST CDS_LIB mstr_standard
J 0
(-2850 3850);
PAINT MONO (-2850 3850);
DISPLAY INVISIBLE (-2850 3850);
FORCEPROP 1 LAST BODY_TYPE PLUMBING
J 2
(-2850 3800);
DISPLAY 1.595745 (-2850 3800);
PAINT GREEN (-2850 3800);
DISPLAY INVISIBLE (-2850 3800);
FORCEPROP 1 LAST HDL_TAP TRUE
J 2
(-3175 3725);
DISPLAY 1.595745 (-3175 3725);
PAINT GREEN (-3175 3725);
DISPLAY INVISIBLE (-3175 3725);
FORCEPROP 1 LAST PATH I144
J 2
(-2848 3850);
DISPLAY 0.872340 (-2848 3850);
PAINT GREEN (-2848 3850);
DISPLAY INVISIBLE (-2848 3850);
FORCEADD TAP..6
R 2
(-2850 3950);
FORCEPROP 3 LASTPIN (-2900 3950) SIG_NAME M_C_DQS_DP<2>
J 0
(-2890 3960);
DISPLAY 0.659574 (-2890 3960);
PAINT MONO (-2890 3960);
DISPLAY INVISIBLE (-2890 3960);
FORCEPROP 1 LASTPIN (-2900 3950) BN 2
J 2
(-2848 3958);
DISPLAY 0.617021 (-2848 3958);
PAINT PINK (-2848 3958);
FORCEPROP 2 LAST CDS_LIB mstr_standard
J 0
(-2850 3950);
PAINT MONO (-2850 3950);
DISPLAY INVISIBLE (-2850 3950);
FORCEPROP 1 LAST BODY_TYPE PLUMBING
J 2
(-2850 3900);
DISPLAY 1.595745 (-2850 3900);
PAINT GREEN (-2850 3900);
DISPLAY INVISIBLE (-2850 3900);
FORCEPROP 1 LAST HDL_TAP TRUE
J 2
(-3175 3825);
DISPLAY 1.595745 (-3175 3825);
PAINT GREEN (-3175 3825);
DISPLAY INVISIBLE (-3175 3825);
FORCEPROP 1 LAST PATH I145
J 2
(-2848 3950);
DISPLAY 0.872340 (-2848 3950);
PAINT GREEN (-2848 3950);
DISPLAY INVISIBLE (-2848 3950);
FORCEADD TAP..6
R 2
(-2850 4000);
FORCEPROP 3 LASTPIN (-2900 4000) SIG_NAME M_C_DQS_DP<3>
J 0
(-2890 4010);
DISPLAY 0.659574 (-2890 4010);
PAINT MONO (-2890 4010);
DISPLAY INVISIBLE (-2890 4010);
FORCEPROP 1 LASTPIN (-2900 4000) BN 3
J 2
(-2848 4008);
DISPLAY 0.617021 (-2848 4008);
PAINT PINK (-2848 4008);
FORCEPROP 2 LAST CDS_LIB mstr_standard
J 0
(-2850 4000);
PAINT MONO (-2850 4000);
DISPLAY INVISIBLE (-2850 4000);
FORCEPROP 1 LAST BODY_TYPE PLUMBING
J 2
(-2850 3950);
DISPLAY 1.595745 (-2850 3950);
PAINT GREEN (-2850 3950);
DISPLAY INVISIBLE (-2850 3950);
FORCEPROP 1 LAST HDL_TAP TRUE
J 2
(-3175 3875);
DISPLAY 1.595745 (-3175 3875);
PAINT GREEN (-3175 3875);
DISPLAY INVISIBLE (-3175 3875);
FORCEPROP 1 LAST PATH I146
J 2
(-2848 4000);
DISPLAY 0.872340 (-2848 4000);
PAINT GREEN (-2848 4000);
DISPLAY INVISIBLE (-2848 4000);
FORCEADD OFFPAGE..2
(-2000 550);
FORCEPROP 2 LAST $XR0 47 
J 0
(-1811 550);
DISPLAY 0.638298 (-1811 550);
PAINT MONO (-1811 550);
FORCEPROP 2 LAST $XR1 48 
J 0
(-1721 550);
DISPLAY 0.638298 (-1721 550);
PAINT MONO (-1721 550);
FORCEPROP 2 LAST CDS_LIB mstr_standard
J 0
(-2000 550);
PAINT MONO (-2000 550);
DISPLAY INVISIBLE (-2000 550);
FORCEPROP 1 LAST OFFPAGE TRUE
J 0
(-1675 425);
DISPLAY 1.170213 (-1675 425);
PAINT GREEN (-1675 425);
DISPLAY INVISIBLE (-1675 425);
FORCEPROP 1 LAST COMMENT_BODY TRUE
J 0
(-2045 455);
DISPLAY 1.170213 (-2045 455);
PAINT GREEN (-2045 455);
DISPLAY INVISIBLE (-2045 455);
FORCEPROP 2 LAST PATH I147
J 0
(-1825 625);
DISPLAY 1.021277 (-1825 625);
PAINT ORANGE (-1825 625);
DISPLAY INVISIBLE (-1825 625);
FORCEADD OFFPAGE..2
(-2000 650);
FORCEPROP 2 LAST $XR0 47 
J 0
(-1811 650);
DISPLAY 0.638298 (-1811 650);
PAINT MONO (-1811 650);
FORCEPROP 2 LAST $XR1 48 
J 0
(-1721 650);
DISPLAY 0.638298 (-1721 650);
PAINT MONO (-1721 650);
FORCEPROP 2 LAST CDS_LIB mstr_standard
J 0
(-2000 650);
PAINT MONO (-2000 650);
DISPLAY INVISIBLE (-2000 650);
FORCEPROP 1 LAST OFFPAGE TRUE
J 0
(-1675 525);
DISPLAY 1.170213 (-1675 525);
PAINT GREEN (-1675 525);
DISPLAY INVISIBLE (-1675 525);
FORCEPROP 1 LAST COMMENT_BODY TRUE
J 0
(-2045 555);
DISPLAY 1.170213 (-2045 555);
PAINT GREEN (-2045 555);
DISPLAY INVISIBLE (-2045 555);
FORCEPROP 2 LAST PATH I148
J 0
(-1825 725);
DISPLAY 1.021277 (-1825 725);
PAINT ORANGE (-1825 725);
DISPLAY INVISIBLE (-1825 725);
FORCEADD OFFPAGE..4
(-2000 600);
FORCEPROP 2 LAST $XR0 47 
J 0
(-1814 600);
DISPLAY 0.638298 (-1814 600);
PAINT MONO (-1814 600);
FORCEPROP 2 LAST $XR1 48 
J 0
(-1724 600);
DISPLAY 0.638298 (-1724 600);
PAINT MONO (-1724 600);
FORCEPROP 2 LAST CDS_LIB mstr_standard
J 0
(-2000 600);
PAINT MONO (-2000 600);
DISPLAY INVISIBLE (-2000 600);
FORCEPROP 1 LAST OFFPAGE TRUE
J 0
(-1675 475);
DISPLAY 1.170213 (-1675 475);
PAINT GREEN (-1675 475);
DISPLAY INVISIBLE (-1675 475);
FORCEPROP 1 LAST COMMENT_BODY TRUE
J 0
(-2025 500);
DISPLAY 1.170213 (-2025 500);
PAINT GREEN (-2025 500);
DISPLAY INVISIBLE (-2025 500);
FORCEPROP 2 LAST PATH I149
J 0
(-1825 675);
DISPLAY 1.021277 (-1825 675);
PAINT ORANGE (-1825 675);
DISPLAY INVISIBLE (-1825 675);
FORCEADD TAP..6
(-5575 1200);
FORCEPROP 3 LASTPIN (-5525 1200) SIG_NAME M_C_ECC<2>
J 0
(-5515 1210);
DISPLAY 0.659574 (-5515 1210);
PAINT MONO (-5515 1210);
DISPLAY INVISIBLE (-5515 1210);
FORCEPROP 1 LASTPIN (-5525 1200) BN 2
J 0
(-5577 1208);
DISPLAY 0.617021 (-5577 1208);
PAINT PINK (-5577 1208);
FORCEPROP 2 LAST CDS_LIB mstr_standard
J 0
(-5575 1200);
PAINT MONO (-5575 1200);
DISPLAY INVISIBLE (-5575 1200);
FORCEPROP 1 LAST BODY_TYPE PLUMBING
J 0
(-5575 1150);
DISPLAY 1.595745 (-5575 1150);
PAINT GREEN (-5575 1150);
DISPLAY INVISIBLE (-5575 1150);
FORCEPROP 1 LAST HDL_TAP TRUE
J 0
(-5250 1075);
DISPLAY 1.595745 (-5250 1075);
PAINT GREEN (-5250 1075);
DISPLAY INVISIBLE (-5250 1075);
FORCEPROP 1 LAST PATH I15
J 0
(-5577 1200);
DISPLAY 0.872340 (-5577 1200);
PAINT GREEN (-5577 1200);
DISPLAY INVISIBLE (-5577 1200);
FORCEADD OFFPAGE..2
(-2000 950);
FORCEPROP 2 LAST $XR0 47 
J 0
(-1811 950);
DISPLAY 0.638298 (-1811 950);
PAINT MONO (-1811 950);
FORCEPROP 2 LAST $XR1 48 
J 0
(-1721 950);
DISPLAY 0.638298 (-1721 950);
PAINT MONO (-1721 950);
FORCEPROP 2 LAST CDS_LIB mstr_standard
J 0
(-2000 950);
PAINT MONO (-2000 950);
DISPLAY INVISIBLE (-2000 950);
FORCEPROP 1 LAST OFFPAGE TRUE
J 0
(-1675 825);
DISPLAY 1.170213 (-1675 825);
PAINT GREEN (-1675 825);
DISPLAY INVISIBLE (-1675 825);
FORCEPROP 1 LAST COMMENT_BODY TRUE
J 0
(-2045 855);
DISPLAY 1.170213 (-2045 855);
PAINT GREEN (-2045 855);
DISPLAY INVISIBLE (-2045 855);
FORCEPROP 2 LAST PATH I150
J 0
(-1825 1025);
DISPLAY 1.021277 (-1825 1025);
PAINT ORANGE (-1825 1025);
DISPLAY INVISIBLE (-1825 1025);
FORCEADD OFFPAGE..2
(-2000 850);
FORCEPROP 2 LAST $XR0 47 
J 0
(-1811 850);
DISPLAY 0.638298 (-1811 850);
PAINT MONO (-1811 850);
FORCEPROP 2 LAST $XR1 48 
J 0
(-1721 850);
DISPLAY 0.638298 (-1721 850);
PAINT MONO (-1721 850);
FORCEPROP 2 LAST CDS_LIB mstr_standard
J 0
(-2000 850);
PAINT MONO (-2000 850);
DISPLAY INVISIBLE (-2000 850);
FORCEPROP 1 LAST OFFPAGE TRUE
J 0
(-1675 725);
DISPLAY 1.170213 (-1675 725);
PAINT GREEN (-1675 725);
DISPLAY INVISIBLE (-1675 725);
FORCEPROP 1 LAST COMMENT_BODY TRUE
J 0
(-2045 755);
DISPLAY 1.170213 (-2045 755);
PAINT GREEN (-2045 755);
DISPLAY INVISIBLE (-2045 755);
FORCEPROP 2 LAST PATH I151
J 0
(-1825 925);
DISPLAY 1.021277 (-1825 925);
PAINT ORANGE (-1825 925);
DISPLAY INVISIBLE (-1825 925);
FORCEADD OFFPAGE..2
(-2000 1400);
FORCEPROP 2 LAST $XR0 47 
J 0
(-1811 1400);
DISPLAY 0.638298 (-1811 1400);
PAINT MONO (-1811 1400);
FORCEPROP 2 LAST $XR1 48 
J 0
(-1721 1400);
DISPLAY 0.638298 (-1721 1400);
PAINT MONO (-1721 1400);
FORCEPROP 2 LAST CDS_LIB mstr_standard
J 0
(-2000 1400);
PAINT MONO (-2000 1400);
DISPLAY INVISIBLE (-2000 1400);
FORCEPROP 1 LAST OFFPAGE TRUE
J 0
(-1675 1275);
DISPLAY 1.170213 (-1675 1275);
PAINT GREEN (-1675 1275);
DISPLAY INVISIBLE (-1675 1275);
FORCEPROP 1 LAST COMMENT_BODY TRUE
J 0
(-2045 1305);
DISPLAY 1.170213 (-2045 1305);
PAINT GREEN (-2045 1305);
DISPLAY INVISIBLE (-2045 1305);
FORCEPROP 2 LAST PATH I152
J 0
(-1825 1475);
DISPLAY 1.021277 (-1825 1475);
PAINT ORANGE (-1825 1475);
DISPLAY INVISIBLE (-1825 1475);
FORCEADD OFFPAGE..2
(-2000 1900);
FORCEPROP 2 LAST $XR0 47 
J 0
(-1811 1900);
DISPLAY 0.638298 (-1811 1900);
PAINT MONO (-1811 1900);
FORCEPROP 2 LAST $XR1 48 
J 0
(-1721 1900);
DISPLAY 0.638298 (-1721 1900);
PAINT MONO (-1721 1900);
FORCEPROP 2 LAST CDS_LIB mstr_standard
J 0
(-2000 1900);
PAINT MONO (-2000 1900);
DISPLAY INVISIBLE (-2000 1900);
FORCEPROP 1 LAST OFFPAGE TRUE
J 0
(-1675 1775);
DISPLAY 1.170213 (-1675 1775);
PAINT GREEN (-1675 1775);
DISPLAY INVISIBLE (-1675 1775);
FORCEPROP 1 LAST COMMENT_BODY TRUE
J 0
(-2045 1805);
DISPLAY 1.170213 (-2045 1805);
PAINT GREEN (-2045 1805);
DISPLAY INVISIBLE (-2045 1805);
FORCEPROP 2 LAST PATH I153
J 0
(-1825 1975);
DISPLAY 1.021277 (-1825 1975);
PAINT ORANGE (-1825 1975);
DISPLAY INVISIBLE (-1825 1975);
FORCEADD OFFPAGE..2
(-2000 1650);
FORCEPROP 2 LAST $XR0 47 
J 0
(-1811 1650);
DISPLAY 0.638298 (-1811 1650);
PAINT MONO (-1811 1650);
FORCEPROP 2 LAST $XR1 48 
J 0
(-1721 1650);
DISPLAY 0.638298 (-1721 1650);
PAINT MONO (-1721 1650);
FORCEPROP 2 LAST CDS_LIB mstr_standard
J 0
(-2000 1650);
PAINT MONO (-2000 1650);
DISPLAY INVISIBLE (-2000 1650);
FORCEPROP 1 LAST OFFPAGE TRUE
J 0
(-1675 1525);
DISPLAY 1.170213 (-1675 1525);
PAINT GREEN (-1675 1525);
DISPLAY INVISIBLE (-1675 1525);
FORCEPROP 1 LAST COMMENT_BODY TRUE
J 0
(-2045 1555);
DISPLAY 1.170213 (-2045 1555);
PAINT GREEN (-2045 1555);
DISPLAY INVISIBLE (-2045 1555);
FORCEPROP 2 LAST PATH I154
J 0
(-1825 1725);
DISPLAY 1.021277 (-1825 1725);
PAINT ORANGE (-1825 1725);
DISPLAY INVISIBLE (-1825 1725);
FORCEADD OFFPAGE..2
(-2000 2850);
FORCEPROP 2 LAST $XR0 47 
J 0
(-1811 2850);
DISPLAY 0.638298 (-1811 2850);
PAINT MONO (-1811 2850);
FORCEPROP 2 LAST $XR1 48 
J 0
(-1721 2850);
DISPLAY 0.638298 (-1721 2850);
PAINT MONO (-1721 2850);
FORCEPROP 2 LAST CDS_LIB mstr_standard
J 0
(-2000 2850);
PAINT MONO (-2000 2850);
DISPLAY INVISIBLE (-2000 2850);
FORCEPROP 1 LAST OFFPAGE TRUE
J 0
(-1675 2725);
DISPLAY 1.170213 (-1675 2725);
PAINT GREEN (-1675 2725);
DISPLAY INVISIBLE (-1675 2725);
FORCEPROP 1 LAST COMMENT_BODY TRUE
J 0
(-2045 2755);
DISPLAY 1.170213 (-2045 2755);
PAINT GREEN (-2045 2755);
DISPLAY INVISIBLE (-2045 2755);
FORCEPROP 2 LAST PATH I155
J 0
(-1825 2925);
DISPLAY 1.021277 (-1825 2925);
PAINT ORANGE (-1825 2925);
DISPLAY INVISIBLE (-1825 2925);
FORCEADD OFFPAGE..3
(-2000 3800);
FORCEPROP 2 LAST $XR0 47 
J 0
(-1786 3800);
DISPLAY 0.638298 (-1786 3800);
PAINT MONO (-1786 3800);
FORCEPROP 2 LAST $XR1 48 
J 0
(-1696 3800);
DISPLAY 0.638298 (-1696 3800);
PAINT MONO (-1696 3800);
FORCEPROP 2 LAST CDS_LIB mstr_standard
J 0
(-2000 3800);
PAINT MONO (-2000 3800);
DISPLAY INVISIBLE (-2000 3800);
FORCEPROP 1 LAST OFFPAGE TRUE
J 0
(-1675 3675);
DISPLAY 1.170213 (-1675 3675);
PAINT GREEN (-1675 3675);
DISPLAY INVISIBLE (-1675 3675);
FORCEPROP 1 LAST COMMENT_BODY TRUE
J 0
(-2050 3700);
DISPLAY 1.170213 (-2050 3700);
PAINT GREEN (-2050 3700);
DISPLAY INVISIBLE (-2050 3700);
FORCEPROP 2 LAST PATH I156
J 0
(-1800 3875);
DISPLAY 1.021277 (-1800 3875);
PAINT ORANGE (-1800 3875);
DISPLAY INVISIBLE (-1800 3875);
FORCEADD TAP..6
R 2
(-2850 4100);
FORCEPROP 3 LASTPIN (-2900 4100) SIG_NAME M_C_DQS_DP<5>
J 0
(-2890 4110);
DISPLAY 0.659574 (-2890 4110);
PAINT MONO (-2890 4110);
DISPLAY INVISIBLE (-2890 4110);
FORCEPROP 1 LASTPIN (-2900 4100) BN 5
J 2
(-2848 4108);
DISPLAY 0.617021 (-2848 4108);
PAINT PINK (-2848 4108);
FORCEPROP 2 LAST CDS_LIB mstr_standard
J 0
(-2850 4100);
PAINT MONO (-2850 4100);
DISPLAY INVISIBLE (-2850 4100);
FORCEPROP 1 LAST BODY_TYPE PLUMBING
J 2
(-2850 4050);
DISPLAY 1.595745 (-2850 4050);
PAINT GREEN (-2850 4050);
DISPLAY INVISIBLE (-2850 4050);
FORCEPROP 1 LAST HDL_TAP TRUE
J 2
(-3175 3975);
DISPLAY 1.595745 (-3175 3975);
PAINT GREEN (-3175 3975);
DISPLAY INVISIBLE (-3175 3975);
FORCEPROP 1 LAST PATH I157
J 2
(-2848 4100);
DISPLAY 0.872340 (-2848 4100);
PAINT GREEN (-2848 4100);
DISPLAY INVISIBLE (-2848 4100);
FORCEADD TAP..6
R 2
(-2850 4050);
FORCEPROP 3 LASTPIN (-2900 4050) SIG_NAME M_C_DQS_DP<4>
J 0
(-2890 4060);
DISPLAY 0.659574 (-2890 4060);
PAINT MONO (-2890 4060);
DISPLAY INVISIBLE (-2890 4060);
FORCEPROP 1 LASTPIN (-2900 4050) BN 4
J 2
(-2848 4058);
DISPLAY 0.617021 (-2848 4058);
PAINT PINK (-2848 4058);
FORCEPROP 2 LAST CDS_LIB mstr_standard
J 0
(-2850 4050);
PAINT MONO (-2850 4050);
DISPLAY INVISIBLE (-2850 4050);
FORCEPROP 1 LAST BODY_TYPE PLUMBING
J 2
(-2850 4000);
DISPLAY 1.595745 (-2850 4000);
PAINT GREEN (-2850 4000);
DISPLAY INVISIBLE (-2850 4000);
FORCEPROP 1 LAST HDL_TAP TRUE
J 2
(-3175 3925);
DISPLAY 1.595745 (-3175 3925);
PAINT GREEN (-3175 3925);
DISPLAY INVISIBLE (-3175 3925);
FORCEPROP 1 LAST PATH I158
J 2
(-2848 4050);
DISPLAY 0.872340 (-2848 4050);
PAINT GREEN (-2848 4050);
DISPLAY INVISIBLE (-2848 4050);
FORCEADD TAP..6
R 2
(-2850 4150);
FORCEPROP 3 LASTPIN (-2900 4150) SIG_NAME M_C_DQS_DP<6>
J 0
(-2890 4160);
DISPLAY 0.659574 (-2890 4160);
PAINT MONO (-2890 4160);
DISPLAY INVISIBLE (-2890 4160);
FORCEPROP 1 LASTPIN (-2900 4150) BN 6
J 2
(-2848 4158);
DISPLAY 0.617021 (-2848 4158);
PAINT PINK (-2848 4158);
FORCEPROP 2 LAST CDS_LIB mstr_standard
J 0
(-2850 4150);
PAINT MONO (-2850 4150);
DISPLAY INVISIBLE (-2850 4150);
FORCEPROP 1 LAST BODY_TYPE PLUMBING
J 2
(-2850 4100);
DISPLAY 1.595745 (-2850 4100);
PAINT GREEN (-2850 4100);
DISPLAY INVISIBLE (-2850 4100);
FORCEPROP 1 LAST HDL_TAP TRUE
J 2
(-3175 4025);
DISPLAY 1.595745 (-3175 4025);
PAINT GREEN (-3175 4025);
DISPLAY INVISIBLE (-3175 4025);
FORCEPROP 1 LAST PATH I159
J 2
(-2848 4150);
DISPLAY 0.872340 (-2848 4150);
PAINT GREEN (-2848 4150);
DISPLAY INVISIBLE (-2848 4150);
FORCEADD TAP..6
(-5575 1300);
FORCEPROP 3 LASTPIN (-5525 1300) SIG_NAME M_C_ECC<4>
J 0
(-5515 1310);
DISPLAY 0.659574 (-5515 1310);
PAINT MONO (-5515 1310);
DISPLAY INVISIBLE (-5515 1310);
FORCEPROP 1 LASTPIN (-5525 1300) BN 4
J 0
(-5577 1308);
DISPLAY 0.617021 (-5577 1308);
PAINT PINK (-5577 1308);
FORCEPROP 2 LAST CDS_LIB mstr_standard
J 0
(-5575 1300);
PAINT MONO (-5575 1300);
DISPLAY INVISIBLE (-5575 1300);
FORCEPROP 1 LAST BODY_TYPE PLUMBING
J 0
(-5575 1250);
DISPLAY 1.595745 (-5575 1250);
PAINT GREEN (-5575 1250);
DISPLAY INVISIBLE (-5575 1250);
FORCEPROP 1 LAST HDL_TAP TRUE
J 0
(-5250 1175);
DISPLAY 1.595745 (-5250 1175);
PAINT GREEN (-5250 1175);
DISPLAY INVISIBLE (-5250 1175);
FORCEPROP 1 LAST PATH I16
J 0
(-5577 1300);
DISPLAY 0.872340 (-5577 1300);
PAINT GREEN (-5577 1300);
DISPLAY INVISIBLE (-5577 1300);
FORCEADD TAP..6
R 2
(-2850 4200);
FORCEPROP 3 LASTPIN (-2900 4200) SIG_NAME M_C_DQS_DP<7>
J 0
(-2890 4210);
DISPLAY 0.659574 (-2890 4210);
PAINT MONO (-2890 4210);
DISPLAY INVISIBLE (-2890 4210);
FORCEPROP 1 LASTPIN (-2900 4200) BN 7
J 2
(-2848 4208);
DISPLAY 0.617021 (-2848 4208);
PAINT PINK (-2848 4208);
FORCEPROP 2 LAST CDS_LIB mstr_standard
J 0
(-2850 4200);
PAINT MONO (-2850 4200);
DISPLAY INVISIBLE (-2850 4200);
FORCEPROP 1 LAST BODY_TYPE PLUMBING
J 2
(-2850 4150);
DISPLAY 1.595745 (-2850 4150);
PAINT GREEN (-2850 4150);
DISPLAY INVISIBLE (-2850 4150);
FORCEPROP 1 LAST HDL_TAP TRUE
J 2
(-3175 4075);
DISPLAY 1.595745 (-3175 4075);
PAINT GREEN (-3175 4075);
DISPLAY INVISIBLE (-3175 4075);
FORCEPROP 1 LAST PATH I160
J 2
(-2848 4200);
DISPLAY 0.872340 (-2848 4200);
PAINT GREEN (-2848 4200);
DISPLAY INVISIBLE (-2848 4200);
FORCEADD TAP..6
R 2
(-2850 4250);
FORCEPROP 3 LASTPIN (-2900 4250) SIG_NAME M_C_DQS_DP<8>
J 0
(-2890 4260);
DISPLAY 0.659574 (-2890 4260);
PAINT MONO (-2890 4260);
DISPLAY INVISIBLE (-2890 4260);
FORCEPROP 1 LASTPIN (-2900 4250) BN 8
J 2
(-2848 4258);
DISPLAY 0.617021 (-2848 4258);
PAINT PINK (-2848 4258);
FORCEPROP 2 LAST CDS_LIB mstr_standard
J 0
(-2850 4250);
PAINT MONO (-2850 4250);
DISPLAY INVISIBLE (-2850 4250);
FORCEPROP 1 LAST BODY_TYPE PLUMBING
J 2
(-2850 4200);
DISPLAY 1.595745 (-2850 4200);
PAINT GREEN (-2850 4200);
DISPLAY INVISIBLE (-2850 4200);
FORCEPROP 1 LAST HDL_TAP TRUE
J 2
(-3175 4125);
DISPLAY 1.595745 (-3175 4125);
PAINT GREEN (-3175 4125);
DISPLAY INVISIBLE (-3175 4125);
FORCEPROP 1 LAST PATH I161
J 2
(-2848 4250);
DISPLAY 0.872340 (-2848 4250);
PAINT GREEN (-2848 4250);
DISPLAY INVISIBLE (-2848 4250);
FORCEADD TAP..6
R 2
(-2850 4300);
FORCEPROP 3 LASTPIN (-2900 4300) SIG_NAME M_C_DQS_DP<9>
J 0
(-2890 4310);
DISPLAY 0.659574 (-2890 4310);
PAINT MONO (-2890 4310);
DISPLAY INVISIBLE (-2890 4310);
FORCEPROP 1 LASTPIN (-2900 4300) BN 9
J 2
(-2848 4308);
DISPLAY 0.617021 (-2848 4308);
PAINT PINK (-2848 4308);
FORCEPROP 2 LAST CDS_LIB mstr_standard
J 0
(-2850 4300);
PAINT MONO (-2850 4300);
DISPLAY INVISIBLE (-2850 4300);
FORCEPROP 1 LAST BODY_TYPE PLUMBING
J 2
(-2850 4250);
DISPLAY 1.595745 (-2850 4250);
PAINT GREEN (-2850 4250);
DISPLAY INVISIBLE (-2850 4250);
FORCEPROP 1 LAST HDL_TAP TRUE
J 2
(-3175 4175);
DISPLAY 1.595745 (-3175 4175);
PAINT GREEN (-3175 4175);
DISPLAY INVISIBLE (-3175 4175);
FORCEPROP 1 LAST PATH I162
J 2
(-2848 4300);
DISPLAY 0.872340 (-2848 4300);
PAINT GREEN (-2848 4300);
DISPLAY INVISIBLE (-2848 4300);
FORCEADD TAP..6
R 2
(-2850 4350);
FORCEPROP 3 LASTPIN (-2900 4350) SIG_NAME M_C_DQS_DP<10>
J 0
(-2890 4360);
DISPLAY 0.659574 (-2890 4360);
PAINT MONO (-2890 4360);
DISPLAY INVISIBLE (-2890 4360);
FORCEPROP 1 LASTPIN (-2900 4350) BN 10
J 2
(-2848 4358);
DISPLAY 0.617021 (-2848 4358);
PAINT PINK (-2848 4358);
FORCEPROP 2 LAST CDS_LIB mstr_standard
J 0
(-2850 4350);
PAINT MONO (-2850 4350);
DISPLAY INVISIBLE (-2850 4350);
FORCEPROP 1 LAST BODY_TYPE PLUMBING
J 2
(-2850 4300);
DISPLAY 1.595745 (-2850 4300);
PAINT GREEN (-2850 4300);
DISPLAY INVISIBLE (-2850 4300);
FORCEPROP 1 LAST HDL_TAP TRUE
J 2
(-3175 4225);
DISPLAY 1.595745 (-3175 4225);
PAINT GREEN (-3175 4225);
DISPLAY INVISIBLE (-3175 4225);
FORCEPROP 1 LAST PATH I163
J 2
(-2848 4350);
DISPLAY 0.872340 (-2848 4350);
PAINT GREEN (-2848 4350);
DISPLAY INVISIBLE (-2848 4350);
FORCEADD TAP..6
R 2
(-2850 4400);
FORCEPROP 3 LASTPIN (-2900 4400) SIG_NAME M_C_DQS_DP<11>
J 0
(-2890 4410);
DISPLAY 0.659574 (-2890 4410);
PAINT MONO (-2890 4410);
DISPLAY INVISIBLE (-2890 4410);
FORCEPROP 1 LASTPIN (-2900 4400) BN 11
J 2
(-2848 4408);
DISPLAY 0.617021 (-2848 4408);
PAINT PINK (-2848 4408);
FORCEPROP 2 LAST CDS_LIB mstr_standard
J 0
(-2850 4400);
PAINT MONO (-2850 4400);
DISPLAY INVISIBLE (-2850 4400);
FORCEPROP 1 LAST BODY_TYPE PLUMBING
J 2
(-2850 4350);
DISPLAY 1.595745 (-2850 4350);
PAINT GREEN (-2850 4350);
DISPLAY INVISIBLE (-2850 4350);
FORCEPROP 1 LAST HDL_TAP TRUE
J 2
(-3175 4275);
DISPLAY 1.595745 (-3175 4275);
PAINT GREEN (-3175 4275);
DISPLAY INVISIBLE (-3175 4275);
FORCEPROP 1 LAST PATH I164
J 2
(-2848 4400);
DISPLAY 0.872340 (-2848 4400);
PAINT GREEN (-2848 4400);
DISPLAY INVISIBLE (-2848 4400);
FORCEADD TAP..6
R 2
(-2850 4450);
FORCEPROP 3 LASTPIN (-2900 4450) SIG_NAME M_C_DQS_DP<12>
J 0
(-2890 4460);
DISPLAY 0.659574 (-2890 4460);
PAINT MONO (-2890 4460);
DISPLAY INVISIBLE (-2890 4460);
FORCEPROP 1 LASTPIN (-2900 4450) BN 12
J 2
(-2848 4458);
DISPLAY 0.617021 (-2848 4458);
PAINT PINK (-2848 4458);
FORCEPROP 2 LAST CDS_LIB mstr_standard
J 0
(-2850 4450);
PAINT MONO (-2850 4450);
DISPLAY INVISIBLE (-2850 4450);
FORCEPROP 1 LAST BODY_TYPE PLUMBING
J 2
(-2850 4400);
DISPLAY 1.595745 (-2850 4400);
PAINT GREEN (-2850 4400);
DISPLAY INVISIBLE (-2850 4400);
FORCEPROP 1 LAST HDL_TAP TRUE
J 2
(-3175 4325);
DISPLAY 1.595745 (-3175 4325);
PAINT GREEN (-3175 4325);
DISPLAY INVISIBLE (-3175 4325);
FORCEPROP 1 LAST PATH I165
J 2
(-2848 4450);
DISPLAY 0.872340 (-2848 4450);
PAINT GREEN (-2848 4450);
DISPLAY INVISIBLE (-2848 4450);
FORCEADD TAP..6
R 2
(-2850 4550);
FORCEPROP 3 LASTPIN (-2900 4550) SIG_NAME M_C_DQS_DP<14>
J 0
(-2890 4560);
DISPLAY 0.659574 (-2890 4560);
PAINT MONO (-2890 4560);
DISPLAY INVISIBLE (-2890 4560);
FORCEPROP 1 LASTPIN (-2900 4550) BN 14
J 2
(-2848 4558);
DISPLAY 0.617021 (-2848 4558);
PAINT PINK (-2848 4558);
FORCEPROP 2 LAST CDS_LIB mstr_standard
J 0
(-2850 4550);
PAINT MONO (-2850 4550);
DISPLAY INVISIBLE (-2850 4550);
FORCEPROP 1 LAST BODY_TYPE PLUMBING
J 2
(-2850 4500);
DISPLAY 1.595745 (-2850 4500);
PAINT GREEN (-2850 4500);
DISPLAY INVISIBLE (-2850 4500);
FORCEPROP 1 LAST HDL_TAP TRUE
J 2
(-3175 4425);
DISPLAY 1.595745 (-3175 4425);
PAINT GREEN (-3175 4425);
DISPLAY INVISIBLE (-3175 4425);
FORCEPROP 1 LAST PATH I166
J 2
(-2848 4550);
DISPLAY 0.872340 (-2848 4550);
PAINT GREEN (-2848 4550);
DISPLAY INVISIBLE (-2848 4550);
FORCEADD TAP..6
R 2
(-2850 4500);
FORCEPROP 3 LASTPIN (-2900 4500) SIG_NAME M_C_DQS_DP<13>
J 0
(-2890 4510);
DISPLAY 0.659574 (-2890 4510);
PAINT MONO (-2890 4510);
DISPLAY INVISIBLE (-2890 4510);
FORCEPROP 1 LASTPIN (-2900 4500) BN 13
J 2
(-2848 4508);
DISPLAY 0.617021 (-2848 4508);
PAINT PINK (-2848 4508);
FORCEPROP 2 LAST CDS_LIB mstr_standard
J 0
(-2850 4500);
PAINT MONO (-2850 4500);
DISPLAY INVISIBLE (-2850 4500);
FORCEPROP 1 LAST BODY_TYPE PLUMBING
J 2
(-2850 4450);
DISPLAY 1.595745 (-2850 4450);
PAINT GREEN (-2850 4450);
DISPLAY INVISIBLE (-2850 4450);
FORCEPROP 1 LAST HDL_TAP TRUE
J 2
(-3175 4375);
DISPLAY 1.595745 (-3175 4375);
PAINT GREEN (-3175 4375);
DISPLAY INVISIBLE (-3175 4375);
FORCEPROP 1 LAST PATH I167
J 2
(-2848 4500);
DISPLAY 0.872340 (-2848 4500);
PAINT GREEN (-2848 4500);
DISPLAY INVISIBLE (-2848 4500);
FORCEADD TAP..6
R 2
(-2850 4600);
FORCEPROP 3 LASTPIN (-2900 4600) SIG_NAME M_C_DQS_DP<15>
J 0
(-2890 4610);
DISPLAY 0.659574 (-2890 4610);
PAINT MONO (-2890 4610);
DISPLAY INVISIBLE (-2890 4610);
FORCEPROP 1 LASTPIN (-2900 4600) BN 15
J 2
(-2848 4608);
DISPLAY 0.617021 (-2848 4608);
PAINT PINK (-2848 4608);
FORCEPROP 2 LAST CDS_LIB mstr_standard
J 0
(-2850 4600);
PAINT MONO (-2850 4600);
DISPLAY INVISIBLE (-2850 4600);
FORCEPROP 1 LAST BODY_TYPE PLUMBING
J 2
(-2850 4550);
DISPLAY 1.595745 (-2850 4550);
PAINT GREEN (-2850 4550);
DISPLAY INVISIBLE (-2850 4550);
FORCEPROP 1 LAST HDL_TAP TRUE
J 2
(-3175 4475);
DISPLAY 1.595745 (-3175 4475);
PAINT GREEN (-3175 4475);
DISPLAY INVISIBLE (-3175 4475);
FORCEPROP 1 LAST PATH I168
J 2
(-2848 4600);
DISPLAY 0.872340 (-2848 4600);
PAINT GREEN (-2848 4600);
DISPLAY INVISIBLE (-2848 4600);
FORCEADD TAP..6
R 2
(-2850 4650);
FORCEPROP 3 LASTPIN (-2900 4650) SIG_NAME M_C_DQS_DP<16>
J 0
(-2890 4660);
DISPLAY 0.659574 (-2890 4660);
PAINT MONO (-2890 4660);
DISPLAY INVISIBLE (-2890 4660);
FORCEPROP 1 LASTPIN (-2900 4650) BN 16
J 2
(-2848 4658);
DISPLAY 0.617021 (-2848 4658);
PAINT PINK (-2848 4658);
FORCEPROP 2 LAST CDS_LIB mstr_standard
J 0
(-2850 4650);
PAINT MONO (-2850 4650);
DISPLAY INVISIBLE (-2850 4650);
FORCEPROP 1 LAST BODY_TYPE PLUMBING
J 2
(-2850 4600);
DISPLAY 1.595745 (-2850 4600);
PAINT GREEN (-2850 4600);
DISPLAY INVISIBLE (-2850 4600);
FORCEPROP 1 LAST HDL_TAP TRUE
J 2
(-3175 4525);
DISPLAY 1.595745 (-3175 4525);
PAINT GREEN (-3175 4525);
DISPLAY INVISIBLE (-3175 4525);
FORCEPROP 1 LAST PATH I169
J 2
(-2848 4650);
DISPLAY 0.872340 (-2848 4650);
PAINT GREEN (-2848 4650);
DISPLAY INVISIBLE (-2848 4650);
FORCEADD TAP..6
(-5575 1250);
FORCEPROP 3 LASTPIN (-5525 1250) SIG_NAME M_C_ECC<3>
J 0
(-5515 1260);
DISPLAY 0.659574 (-5515 1260);
PAINT MONO (-5515 1260);
DISPLAY INVISIBLE (-5515 1260);
FORCEPROP 1 LASTPIN (-5525 1250) BN 3
J 0
(-5577 1258);
DISPLAY 0.617021 (-5577 1258);
PAINT PINK (-5577 1258);
FORCEPROP 2 LAST CDS_LIB mstr_standard
J 0
(-5575 1250);
PAINT MONO (-5575 1250);
DISPLAY INVISIBLE (-5575 1250);
FORCEPROP 1 LAST BODY_TYPE PLUMBING
J 0
(-5575 1200);
DISPLAY 1.595745 (-5575 1200);
PAINT GREEN (-5575 1200);
DISPLAY INVISIBLE (-5575 1200);
FORCEPROP 1 LAST HDL_TAP TRUE
J 0
(-5250 1125);
DISPLAY 1.595745 (-5250 1125);
PAINT GREEN (-5250 1125);
DISPLAY INVISIBLE (-5250 1125);
FORCEPROP 1 LAST PATH I17
J 0
(-5577 1250);
DISPLAY 0.872340 (-5577 1250);
PAINT GREEN (-5577 1250);
DISPLAY INVISIBLE (-5577 1250);
FORCEADD TAP..6
R 2
(-2850 4700);
FORCEPROP 3 LASTPIN (-2900 4700) SIG_NAME M_C_DQS_DP<17>
J 0
(-2890 4710);
DISPLAY 0.659574 (-2890 4710);
PAINT MONO (-2890 4710);
DISPLAY INVISIBLE (-2890 4710);
FORCEPROP 1 LASTPIN (-2900 4700) BN 17
J 2
(-2848 4708);
DISPLAY 0.617021 (-2848 4708);
PAINT PINK (-2848 4708);
FORCEPROP 2 LAST CDS_LIB mstr_standard
J 2
(-2850 4700);
PAINT MONO (-2850 4700);
DISPLAY INVISIBLE (-2850 4700);
FORCEPROP 1 LAST BODY_TYPE PLUMBING
J 2
(-2850 4650);
DISPLAY 1.595745 (-2850 4650);
PAINT GREEN (-2850 4650);
DISPLAY INVISIBLE (-2850 4650);
FORCEPROP 1 LAST HDL_TAP TRUE
J 2
(-3175 4575);
DISPLAY 1.595745 (-3175 4575);
PAINT GREEN (-3175 4575);
DISPLAY INVISIBLE (-3175 4575);
FORCEPROP 1 LAST PATH I170
J 2
(-2848 4700);
DISPLAY 0.872340 (-2848 4700);
PAINT GREEN (-2848 4700);
DISPLAY INVISIBLE (-2848 4700);
FORCEADD OFFPAGE..3
(-2000 4775);
FORCEPROP 2 LAST $XR0 47 
J 0
(-1786 4775);
DISPLAY 0.638298 (-1786 4775);
PAINT MONO (-1786 4775);
FORCEPROP 2 LAST $XR1 48 
J 0
(-1696 4775);
DISPLAY 0.638298 (-1696 4775);
PAINT MONO (-1696 4775);
FORCEPROP 2 LAST CDS_LIB mstr_standard
J 0
(-2000 4775);
PAINT MONO (-2000 4775);
DISPLAY INVISIBLE (-2000 4775);
FORCEPROP 1 LAST OFFPAGE TRUE
J 0
(-1675 4650);
DISPLAY 1.170213 (-1675 4650);
PAINT GREEN (-1675 4650);
DISPLAY INVISIBLE (-1675 4650);
FORCEPROP 1 LAST COMMENT_BODY TRUE
J 0
(-2050 4675);
DISPLAY 1.170213 (-2050 4675);
PAINT GREEN (-2050 4675);
DISPLAY INVISIBLE (-2050 4675);
FORCEPROP 2 LAST PATH I171
J 0
(-1800 4850);
DISPLAY 1.021277 (-1800 4850);
PAINT ORANGE (-1800 4850);
DISPLAY INVISIBLE (-1800 4850);
FORCEADD SKX_EXT_B..5
(-4175 2600);
FORCEPROP 1 LAST LOCATION U5D1
J 0
(-4975 4950);
DISPLAY 0.617021 (-4975 4950);
PAINT AQUA (-4975 4950);
FORCEPROP 1 LAST PART_NUMBER TBD
J 0
(-4975 350);
DISPLAY 0.617021 (-4975 350);
PAINT BLUE (-4975 350);
FORCEPROP 1 LAST MATERIAL IC
J 0
(-4975 4900);
DISPLAY 0.617021 (-4975 4900);
PAINT SKYBLUE (-4975 4900);
FORCEPROP 2 LASTPIN (-3325 550) $PN V53
J 0
(-3315 560);
DISPLAY 0.617021 (-3315 560);
PAINT ORANGE (-3315 560);
FORCEPROP 2 LASTPIN (-3325 1600) $PN AB47
J 0
(-3315 1610);
DISPLAY 0.617021 (-3315 1610);
PAINT ORANGE (-3315 1610);
FORCEPROP 2 LASTPIN (-3325 1550) $PN V49
J 0
(-3315 1560);
DISPLAY 0.617021 (-3315 1560);
PAINT ORANGE (-3315 1560);
FORCEPROP 2 LASTPIN (-3325 1500) $PN AA48
J 0
(-3315 1510);
DISPLAY 0.617021 (-3315 1510);
PAINT ORANGE (-3315 1510);
FORCEPROP 2 LASTPIN (-3325 1450) $PN AA50
J 0
(-3315 1460);
DISPLAY 0.617021 (-3315 1460);
PAINT ORANGE (-3315 1460);
FORCEPROP 2 LASTPIN (-3325 2800) $PN AC46
J 0
(-3315 2810);
DISPLAY 0.617021 (-3315 2810);
PAINT ORANGE (-3315 2810);
FORCEPROP 2 LASTPIN (-3325 2750) $PN AA52
J 0
(-3315 2760);
DISPLAY 0.617021 (-3315 2760);
PAINT ORANGE (-3315 2760);
FORCEPROP 2 LASTPIN (-3325 2700) $PN AE54
J 0
(-3315 2710);
DISPLAY 0.617021 (-3315 2710);
PAINT ORANGE (-3315 2710);
FORCEPROP 2 LASTPIN (-3325 2650) $PN W50
J 0
(-3315 2660);
DISPLAY 0.617021 (-3315 2660);
PAINT ORANGE (-3315 2660);
FORCEPROP 2 LASTPIN (-3325 2600) $PN AD53
J 0
(-3315 2610);
DISPLAY 0.617021 (-3315 2610);
PAINT ORANGE (-3315 2610);
FORCEPROP 2 LASTPIN (-3325 2550) $PN AG62
J 0
(-3315 2560);
DISPLAY 0.617021 (-3315 2560);
PAINT ORANGE (-3315 2560);
FORCEPROP 2 LASTPIN (-3325 2500) $PN AG60
J 0
(-3315 2510);
DISPLAY 0.617021 (-3315 2510);
PAINT ORANGE (-3315 2510);
FORCEPROP 2 LASTPIN (-3325 2450) $PN AD55
J 0
(-3315 2460);
DISPLAY 0.617021 (-3315 2460);
PAINT ORANGE (-3315 2460);
FORCEPROP 2 LASTPIN (-3325 2400) $PN AG58
J 0
(-3315 2410);
DISPLAY 0.617021 (-3315 2410);
PAINT ORANGE (-3315 2410);
FORCEPROP 2 LASTPIN (-3325 2350) $PN AD59
J 0
(-3315 2360);
DISPLAY 0.617021 (-3315 2360);
PAINT ORANGE (-3315 2360);
FORCEPROP 2 LASTPIN (-3325 2300) $PN AE60
J 0
(-3315 2310);
DISPLAY 0.617021 (-3315 2310);
PAINT ORANGE (-3315 2310);
FORCEPROP 2 LASTPIN (-3325 2250) $PN AB59
J 0
(-3315 2260);
DISPLAY 0.617021 (-3315 2260);
PAINT ORANGE (-3315 2260);
FORCEPROP 2 LASTPIN (-3325 2200) $PN V59
J 0
(-3315 2210);
DISPLAY 0.617021 (-3315 2210);
PAINT ORANGE (-3315 2210);
FORCEPROP 2 LASTPIN (-3325 2150) $PN AA58
J 0
(-3315 2160);
DISPLAY 0.617021 (-3315 2160);
PAINT ORANGE (-3315 2160);
FORCEPROP 2 LASTPIN (-3325 2100) $PN W58
J 0
(-3315 2110);
DISPLAY 0.617021 (-3315 2110);
PAINT ORANGE (-3315 2110);
FORCEPROP 2 LASTPIN (-3325 2050) $PN AD57
J 0
(-3315 2060);
DISPLAY 0.617021 (-3315 2060);
PAINT ORANGE (-3315 2060);
FORCEPROP 2 LASTPIN (-3325 2000) $PN AE58
J 0
(-3315 2010);
DISPLAY 0.617021 (-3315 2010);
PAINT ORANGE (-3315 2010);
FORCEPROP 2 LASTPIN (-3325 1950) $PN AB53
J 0
(-3315 1960);
DISPLAY 0.617021 (-3315 1960);
PAINT ORANGE (-3315 1960);
FORCEPROP 2 LASTPIN (-5025 1450) $PN BA70
J 2
(-5035 1460);
DISPLAY 0.617021 (-5035 1460);
PAINT ORANGE (-5035 1460);
FORCEPROP 2 LASTPIN (-5025 1400) $PN AU70
J 2
(-5035 1410);
DISPLAY 0.617021 (-5035 1410);
PAINT ORANGE (-5035 1410);
FORCEPROP 2 LASTPIN (-5025 1350) $PN AY73
J 2
(-5035 1360);
DISPLAY 0.617021 (-5035 1360);
PAINT ORANGE (-5035 1360);
FORCEPROP 2 LASTPIN (-5025 1300) $PN AV73
J 2
(-5035 1310);
DISPLAY 0.617021 (-5035 1310);
PAINT ORANGE (-5035 1310);
FORCEPROP 2 LASTPIN (-5025 1250) $PN AY69
J 2
(-5035 1260);
DISPLAY 0.617021 (-5035 1260);
PAINT ORANGE (-5035 1260);
FORCEPROP 2 LASTPIN (-5025 1200) $PN AV69
J 2
(-5035 1210);
DISPLAY 0.617021 (-5035 1210);
PAINT ORANGE (-5035 1210);
FORCEPROP 2 LASTPIN (-5025 1150) $PN BA72
J 2
(-5035 1160);
DISPLAY 0.617021 (-5035 1160);
PAINT ORANGE (-5035 1160);
FORCEPROP 2 LASTPIN (-5025 1100) $PN AU72
J 2
(-5035 1110);
DISPLAY 0.617021 (-5035 1110);
PAINT ORANGE (-5035 1110);
FORCEPROP 2 LASTPIN (-3325 4700) $PN AV71
J 0
(-3315 4710);
DISPLAY 0.617021 (-3315 4710);
PAINT ORANGE (-3315 4710);
FORCEPROP 2 LASTPIN (-3325 4650) $PN AE24
J 0
(-3315 4660);
DISPLAY 0.617021 (-3315 4660);
PAINT ORANGE (-3315 4660);
FORCEPROP 2 LASTPIN (-3325 4600) $PN AE30
J 0
(-3315 4610);
DISPLAY 0.617021 (-3315 4610);
PAINT ORANGE (-3315 4610);
FORCEPROP 2 LASTPIN (-3325 4550) $PN V33
J 0
(-3315 4560);
DISPLAY 0.617021 (-3315 4560);
PAINT ORANGE (-3315 4560);
FORCEPROP 2 LASTPIN (-3325 4500) $PN V39
J 0
(-3315 4510);
DISPLAY 0.617021 (-3315 4510);
PAINT ORANGE (-3315 4510);
FORCEPROP 2 LASTPIN (-3325 4450) $PN AN66
J 0
(-3315 4460);
DISPLAY 0.617021 (-3315 4460);
PAINT ORANGE (-3315 4460);
FORCEPROP 2 LASTPIN (-3325 4400) $PN V71
J 0
(-3315 4410);
DISPLAY 0.617021 (-3315 4410);
PAINT ORANGE (-3315 4410);
FORCEPROP 2 LASTPIN (-3325 4350) $PN AC76
J 0
(-3315 4360);
DISPLAY 0.617021 (-3315 4360);
PAINT ORANGE (-3315 4360);
FORCEPROP 2 LASTPIN (-3325 4300) $PN AN76
J 0
(-3315 4310);
DISPLAY 0.617021 (-3315 4310);
PAINT ORANGE (-3315 4310);
FORCEPROP 2 LASTPIN (-3325 4250) $PN AY71
J 0
(-3315 4260);
DISPLAY 0.617021 (-3315 4260);
PAINT ORANGE (-3315 4260);
FORCEPROP 2 LASTPIN (-3325 4200) $PN AG24
J 0
(-3315 4210);
DISPLAY 0.617021 (-3315 4210);
PAINT ORANGE (-3315 4210);
FORCEPROP 2 LASTPIN (-3325 4150) $PN AG30
J 0
(-3315 4160);
DISPLAY 0.617021 (-3315 4160);
PAINT ORANGE (-3315 4160);
FORCEPROP 2 LASTPIN (-3325 4100) $PN Y33
J 0
(-3315 4110);
DISPLAY 0.617021 (-3315 4110);
PAINT ORANGE (-3315 4110);
FORCEPROP 2 LASTPIN (-3325 4050) $PN Y39
J 0
(-3315 4060);
DISPLAY 0.617021 (-3315 4060);
PAINT ORANGE (-3315 4060);
FORCEPROP 2 LASTPIN (-3325 4000) $PN AR66
J 0
(-3315 4010);
DISPLAY 0.617021 (-3315 4010);
PAINT ORANGE (-3315 4010);
FORCEPROP 2 LASTPIN (-3325 3950) $PN W70
J 0
(-3315 3960);
DISPLAY 0.617021 (-3315 3960);
PAINT ORANGE (-3315 3960);
FORCEPROP 2 LASTPIN (-3325 3900) $PN AB75
J 0
(-3315 3910);
DISPLAY 0.617021 (-3315 3910);
PAINT ORANGE (-3315 3910);
FORCEPROP 2 LASTPIN (-3325 3850) $PN AM75
J 0
(-3315 3860);
DISPLAY 0.617021 (-3315 3860);
PAINT ORANGE (-3315 3860);
FORCEPROP 2 LASTPIN (-3325 3750) $PN AT71
J 0
(-3315 3760);
DISPLAY 0.617021 (-3315 3760);
PAINT ORANGE (-3315 3760);
FORCEPROP 2 LASTPIN (-3325 3700) $PN AC24
J 0
(-3315 3710);
DISPLAY 0.617021 (-3315 3710);
PAINT ORANGE (-3315 3710);
FORCEPROP 2 LASTPIN (-3325 3650) $PN AC30
J 0
(-3315 3660);
DISPLAY 0.617021 (-3315 3660);
PAINT ORANGE (-3315 3660);
FORCEPROP 2 LASTPIN (-3325 3600) $PN T33
J 0
(-3315 3610);
DISPLAY 0.617021 (-3315 3610);
PAINT ORANGE (-3315 3610);
FORCEPROP 2 LASTPIN (-3325 3550) $PN T39
J 0
(-3315 3560);
DISPLAY 0.617021 (-3315 3560);
PAINT ORANGE (-3315 3560);
FORCEPROP 2 LASTPIN (-3325 3500) $PN AL66
J 0
(-3315 3510);
DISPLAY 0.617021 (-3315 3510);
PAINT ORANGE (-3315 3510);
FORCEPROP 2 LASTPIN (-3325 3450) $PN U72
J 0
(-3315 3460);
DISPLAY 0.617021 (-3315 3460);
PAINT ORANGE (-3315 3460);
FORCEPROP 2 LASTPIN (-3325 3400) $PN AD77
J 0
(-3315 3410);
DISPLAY 0.617021 (-3315 3410);
PAINT ORANGE (-3315 3410);
FORCEPROP 2 LASTPIN (-3325 3350) $PN AP77
J 0
(-3315 3360);
DISPLAY 0.617021 (-3315 3360);
PAINT ORANGE (-3315 3360);
FORCEPROP 2 LASTPIN (-3325 3300) $PN BB71
J 0
(-3315 3310);
DISPLAY 0.617021 (-3315 3310);
PAINT ORANGE (-3315 3310);
FORCEPROP 2 LASTPIN (-3325 3250) $PN AJ24
J 0
(-3315 3260);
DISPLAY 0.617021 (-3315 3260);
PAINT ORANGE (-3315 3260);
FORCEPROP 2 LASTPIN (-3325 3200) $PN AJ30
J 0
(-3315 3210);
DISPLAY 0.617021 (-3315 3210);
PAINT ORANGE (-3315 3210);
FORCEPROP 2 LASTPIN (-3325 3150) $PN AB33
J 0
(-3315 3160);
DISPLAY 0.617021 (-3315 3160);
PAINT ORANGE (-3315 3160);
FORCEPROP 2 LASTPIN (-3325 3100) $PN AB39
J 0
(-3315 3110);
DISPLAY 0.617021 (-3315 3110);
PAINT ORANGE (-3315 3110);
FORCEPROP 2 LASTPIN (-3325 3050) $PN AU66
J 0
(-3315 3060);
DISPLAY 0.617021 (-3315 3060);
PAINT ORANGE (-3315 3060);
FORCEPROP 2 LASTPIN (-3325 3000) $PN Y69
J 0
(-3315 3010);
DISPLAY 0.617021 (-3315 3010);
PAINT ORANGE (-3315 3010);
FORCEPROP 2 LASTPIN (-3325 2950) $PN AA74
J 0
(-3315 2960);
DISPLAY 0.617021 (-3315 2960);
PAINT ORANGE (-3315 2960);
FORCEPROP 2 LASTPIN (-3325 2900) $PN AL74
J 0
(-3315 2910);
DISPLAY 0.617021 (-3315 2910);
PAINT ORANGE (-3315 2910);
FORCEPROP 2 LASTPIN (-5025 4700) $PN AH23
J 2
(-5035 4710);
DISPLAY 0.617021 (-5035 4710);
PAINT ORANGE (-5035 4710);
FORCEPROP 2 LASTPIN (-5025 4650) $PN AD23
J 2
(-5035 4660);
DISPLAY 0.617021 (-5035 4660);
PAINT ORANGE (-5035 4660);
FORCEPROP 2 LASTPIN (-5025 4600) $PN AG26
J 2
(-5035 4610);
DISPLAY 0.617021 (-5035 4610);
PAINT ORANGE (-5035 4610);
FORCEPROP 2 LASTPIN (-5025 4550) $PN AE26
J 2
(-5035 4560);
DISPLAY 0.617021 (-5035 4560);
PAINT ORANGE (-5035 4560);
FORCEPROP 2 LASTPIN (-5025 4500) $PN AG22
J 2
(-5035 4510);
DISPLAY 0.617021 (-5035 4510);
PAINT ORANGE (-5035 4510);
FORCEPROP 2 LASTPIN (-5025 4450) $PN AE22
J 2
(-5035 4460);
DISPLAY 0.617021 (-5035 4460);
PAINT ORANGE (-5035 4460);
FORCEPROP 2 LASTPIN (-5025 4400) $PN AH25
J 2
(-5035 4410);
DISPLAY 0.617021 (-5035 4410);
PAINT ORANGE (-5035 4410);
FORCEPROP 2 LASTPIN (-5025 4350) $PN AD25
J 2
(-5035 4360);
DISPLAY 0.617021 (-5035 4360);
PAINT ORANGE (-5035 4360);
FORCEPROP 2 LASTPIN (-5025 4300) $PN AH29
J 2
(-5035 4310);
DISPLAY 0.617021 (-5035 4310);
PAINT ORANGE (-5035 4310);
FORCEPROP 2 LASTPIN (-5025 4250) $PN AD29
J 2
(-5035 4260);
DISPLAY 0.617021 (-5035 4260);
PAINT ORANGE (-5035 4260);
FORCEPROP 2 LASTPIN (-5025 4200) $PN AG32
J 2
(-5035 4210);
DISPLAY 0.617021 (-5035 4210);
PAINT ORANGE (-5035 4210);
FORCEPROP 2 LASTPIN (-5025 4150) $PN AE32
J 2
(-5035 4160);
DISPLAY 0.617021 (-5035 4160);
PAINT ORANGE (-5035 4160);
FORCEPROP 2 LASTPIN (-5025 4100) $PN AG28
J 2
(-5035 4110);
DISPLAY 0.617021 (-5035 4110);
PAINT ORANGE (-5035 4110);
FORCEPROP 2 LASTPIN (-5025 4050) $PN AE28
J 2
(-5035 4060);
DISPLAY 0.617021 (-5035 4060);
PAINT ORANGE (-5035 4060);
FORCEPROP 2 LASTPIN (-5025 4000) $PN AH31
J 2
(-5035 4010);
DISPLAY 0.617021 (-5035 4010);
PAINT ORANGE (-5035 4010);
FORCEPROP 2 LASTPIN (-5025 3950) $PN AD31
J 2
(-5035 3960);
DISPLAY 0.617021 (-5035 3960);
PAINT ORANGE (-5035 3960);
FORCEPROP 2 LASTPIN (-5025 3900) $PN AA32
J 2
(-5035 3910);
DISPLAY 0.617021 (-5035 3910);
PAINT ORANGE (-5035 3910);
FORCEPROP 2 LASTPIN (-5025 3850) $PN U32
J 2
(-5035 3860);
DISPLAY 0.617021 (-5035 3860);
PAINT ORANGE (-5035 3860);
FORCEPROP 2 LASTPIN (-5025 3800) $PN Y35
J 2
(-5035 3810);
DISPLAY 0.617021 (-5035 3810);
PAINT ORANGE (-5035 3810);
FORCEPROP 2 LASTPIN (-5025 3750) $PN V35
J 2
(-5035 3760);
DISPLAY 0.617021 (-5035 3760);
PAINT ORANGE (-5035 3760);
FORCEPROP 2 LASTPIN (-5025 3700) $PN Y31
J 2
(-5035 3710);
DISPLAY 0.617021 (-5035 3710);
PAINT ORANGE (-5035 3710);
FORCEPROP 2 LASTPIN (-5025 3650) $PN V31
J 2
(-5035 3660);
DISPLAY 0.617021 (-5035 3660);
PAINT ORANGE (-5035 3660);
FORCEPROP 2 LASTPIN (-5025 3600) $PN AA34
J 2
(-5035 3610);
DISPLAY 0.617021 (-5035 3610);
PAINT ORANGE (-5035 3610);
FORCEPROP 2 LASTPIN (-5025 3550) $PN U34
J 2
(-5035 3560);
DISPLAY 0.617021 (-5035 3560);
PAINT ORANGE (-5035 3560);
FORCEPROP 2 LASTPIN (-5025 3500) $PN AA38
J 2
(-5035 3510);
DISPLAY 0.617021 (-5035 3510);
PAINT ORANGE (-5035 3510);
FORCEPROP 2 LASTPIN (-5025 3450) $PN U38
J 2
(-5035 3460);
DISPLAY 0.617021 (-5035 3460);
PAINT ORANGE (-5035 3460);
FORCEPROP 2 LASTPIN (-5025 3400) $PN Y41
J 2
(-5035 3410);
DISPLAY 0.617021 (-5035 3410);
PAINT ORANGE (-5035 3410);
FORCEPROP 2 LASTPIN (-5025 3350) $PN V41
J 2
(-5035 3360);
DISPLAY 0.617021 (-5035 3360);
PAINT ORANGE (-5035 3360);
FORCEPROP 2 LASTPIN (-5025 3300) $PN Y37
J 2
(-5035 3310);
DISPLAY 0.617021 (-5035 3310);
PAINT ORANGE (-5035 3310);
FORCEPROP 2 LASTPIN (-5025 3250) $PN V37
J 2
(-5035 3260);
DISPLAY 0.617021 (-5035 3260);
PAINT ORANGE (-5035 3260);
FORCEPROP 2 LASTPIN (-5025 3200) $PN AA40
J 2
(-5035 3210);
DISPLAY 0.617021 (-5035 3210);
PAINT ORANGE (-5035 3210);
FORCEPROP 2 LASTPIN (-5025 3150) $PN U40
J 2
(-5035 3160);
DISPLAY 0.617021 (-5035 3160);
PAINT ORANGE (-5035 3160);
FORCEPROP 2 LASTPIN (-5025 3100) $PN AT65
J 2
(-5035 3110);
DISPLAY 0.617021 (-5035 3110);
PAINT ORANGE (-5035 3110);
FORCEPROP 2 LASTPIN (-5025 3050) $PN AM65
J 2
(-5035 3060);
DISPLAY 0.617021 (-5035 3060);
PAINT ORANGE (-5035 3060);
FORCEPROP 2 LASTPIN (-5025 3000) $PN AR68
J 2
(-5035 3010);
DISPLAY 0.617021 (-5035 3010);
PAINT ORANGE (-5035 3010);
FORCEPROP 2 LASTPIN (-5025 2950) $PN AN68
J 2
(-5035 2960);
DISPLAY 0.617021 (-5035 2960);
PAINT ORANGE (-5035 2960);
FORCEPROP 2 LASTPIN (-5025 2900) $PN AR64
J 2
(-5035 2910);
DISPLAY 0.617021 (-5035 2910);
PAINT ORANGE (-5035 2910);
FORCEPROP 2 LASTPIN (-5025 2850) $PN AN64
J 2
(-5035 2860);
DISPLAY 0.617021 (-5035 2860);
PAINT ORANGE (-5035 2860);
FORCEPROP 2 LASTPIN (-5025 2800) $PN AT67
J 2
(-5035 2810);
DISPLAY 0.617021 (-5035 2810);
PAINT ORANGE (-5035 2810);
FORCEPROP 2 LASTPIN (-5025 2750) $PN AM67
J 2
(-5035 2760);
DISPLAY 0.617021 (-5035 2760);
PAINT ORANGE (-5035 2760);
FORCEPROP 2 LASTPIN (-5025 2700) $PN V69
J 2
(-5035 2710);
DISPLAY 0.617021 (-5035 2710);
PAINT ORANGE (-5035 2710);
FORCEPROP 2 LASTPIN (-5025 2650) $PN T71
J 2
(-5035 2660);
DISPLAY 0.617021 (-5035 2660);
PAINT ORANGE (-5035 2660);
FORCEPROP 2 LASTPIN (-5025 2600) $PN AB71
J 2
(-5035 2610);
DISPLAY 0.617021 (-5035 2610);
PAINT ORANGE (-5035 2610);
FORCEPROP 2 LASTPIN (-5025 2550) $PN AA72
J 2
(-5035 2560);
DISPLAY 0.617021 (-5035 2560);
PAINT ORANGE (-5035 2560);
FORCEPROP 2 LASTPIN (-5025 2500) $PN T69
J 2
(-5035 2510);
DISPLAY 0.617021 (-5035 2510);
PAINT ORANGE (-5035 2510);
FORCEPROP 2 LASTPIN (-5025 2450) $PN R70
J 2
(-5035 2460);
DISPLAY 0.617021 (-5035 2460);
PAINT ORANGE (-5035 2460);
FORCEPROP 2 LASTPIN (-5025 2400) $PN AA70
J 2
(-5035 2410);
DISPLAY 0.617021 (-5035 2410);
PAINT ORANGE (-5035 2410);
FORCEPROP 2 LASTPIN (-5025 2350) $PN W72
J 2
(-5035 2360);
DISPLAY 0.617021 (-5035 2360);
PAINT ORANGE (-5035 2360);
FORCEPROP 2 LASTPIN (-5025 2300) $PN Y75
J 2
(-5035 2310);
DISPLAY 0.617021 (-5035 2310);
PAINT ORANGE (-5035 2310);
FORCEPROP 2 LASTPIN (-5025 2250) $PN AB77
J 2
(-5035 2260);
DISPLAY 0.617021 (-5035 2260);
PAINT ORANGE (-5035 2260);
FORCEPROP 2 LASTPIN (-5025 2200) $PN AE74
J 2
(-5035 2210);
DISPLAY 0.617021 (-5035 2210);
PAINT ORANGE (-5035 2210);
FORCEPROP 2 LASTPIN (-5025 2150) $PN AF75
J 2
(-5035 2160);
DISPLAY 0.617021 (-5035 2160);
PAINT ORANGE (-5035 2160);
FORCEPROP 2 LASTPIN (-5025 2100) $PN W76
J 2
(-5035 2110);
DISPLAY 0.617021 (-5035 2110);
PAINT ORANGE (-5035 2110);
FORCEPROP 2 LASTPIN (-5025 2050) $PN Y77
J 2
(-5035 2060);
DISPLAY 0.617021 (-5035 2060);
PAINT ORANGE (-5035 2060);
FORCEPROP 2 LASTPIN (-5025 2000) $PN AC74
J 2
(-5035 2010);
DISPLAY 0.617021 (-5035 2010);
PAINT ORANGE (-5035 2010);
FORCEPROP 2 LASTPIN (-5025 1950) $PN AE76
J 2
(-5035 1960);
DISPLAY 0.617021 (-5035 1960);
PAINT ORANGE (-5035 1960);
FORCEPROP 2 LASTPIN (-5025 1900) $PN AK75
J 2
(-5035 1910);
DISPLAY 0.617021 (-5035 1910);
PAINT ORANGE (-5035 1910);
FORCEPROP 2 LASTPIN (-5025 1850) $PN AM77
J 2
(-5035 1860);
DISPLAY 0.617021 (-5035 1860);
PAINT ORANGE (-5035 1860);
FORCEPROP 2 LASTPIN (-5025 1800) $PN AR74
J 2
(-5035 1810);
DISPLAY 0.617021 (-5035 1810);
PAINT ORANGE (-5035 1810);
FORCEPROP 2 LASTPIN (-5025 1750) $PN AT75
J 2
(-5035 1760);
DISPLAY 0.617021 (-5035 1760);
PAINT ORANGE (-5035 1760);
FORCEPROP 2 LASTPIN (-5025 1700) $PN AJ76
J 2
(-5035 1710);
DISPLAY 0.617021 (-5035 1710);
PAINT ORANGE (-5035 1710);
FORCEPROP 2 LASTPIN (-5025 1650) $PN AK77
J 2
(-5035 1660);
DISPLAY 0.617021 (-5035 1660);
PAINT ORANGE (-5035 1660);
FORCEPROP 2 LASTPIN (-5025 1600) $PN AN74
J 2
(-5035 1610);
DISPLAY 0.617021 (-5035 1610);
PAINT ORANGE (-5035 1610);
FORCEPROP 2 LASTPIN (-5025 1550) $PN AR76
J 2
(-5035 1560);
DISPLAY 0.617021 (-5035 1560);
PAINT ORANGE (-5035 1560);
FORCEPROP 2 LASTPIN (-3325 1350) $PN V45
J 0
(-3315 1360);
DISPLAY 0.617021 (-3315 1360);
PAINT ORANGE (-3315 1360);
FORCEPROP 2 LASTPIN (-3325 1300) $PN T45
J 0
(-3315 1310);
DISPLAY 0.617021 (-3315 1310);
PAINT ORANGE (-3315 1310);
FORCEPROP 2 LASTPIN (-3325 1250) $PN W48
J 0
(-3315 1260);
DISPLAY 0.617021 (-3315 1260);
PAINT ORANGE (-3315 1260);
FORCEPROP 2 LASTPIN (-3325 1200) $PN AB51
J 0
(-3315 1210);
DISPLAY 0.617021 (-3315 1210);
PAINT ORANGE (-3315 1210);
FORCEPROP 2 LASTPIN (-3325 1150) $PN AA46
J 0
(-3315 1160);
DISPLAY 0.617021 (-3315 1160);
PAINT ORANGE (-3315 1160);
FORCEPROP 2 LASTPIN (-3325 1100) $PN W46
J 0
(-3315 1110);
DISPLAY 0.617021 (-3315 1110);
PAINT ORANGE (-3315 1110);
FORCEPROP 2 LASTPIN (-3325 1050) $PN AB49
J 0
(-3315 1060);
DISPLAY 0.617021 (-3315 1060);
PAINT ORANGE (-3315 1060);
FORCEPROP 2 LASTPIN (-3325 1000) $PN V51
J 0
(-3315 1010);
DISPLAY 0.617021 (-3315 1010);
PAINT ORANGE (-3315 1010);
FORCEPROP 2 LASTPIN (-5025 1000) $PN V57
J 2
(-5035 1010);
DISPLAY 0.617021 (-5035 1010);
PAINT ORANGE (-5035 1010);
FORCEPROP 2 LASTPIN (-5025 950) $PN AB57
J 2
(-5035 960);
DISPLAY 0.617021 (-5035 960);
PAINT ORANGE (-5035 960);
FORCEPROP 2 LASTPIN (-5025 900) $PN V55
J 2
(-5035 910);
DISPLAY 0.617021 (-5035 910);
PAINT ORANGE (-5035 910);
FORCEPROP 2 LASTPIN (-5025 850) $PN AB55
J 2
(-5035 860);
DISPLAY 0.617021 (-5035 860);
PAINT ORANGE (-5035 860);
FORCEPROP 2 LASTPIN (-5025 800) $PN W56
J 2
(-5035 810);
DISPLAY 0.617021 (-5035 810);
PAINT ORANGE (-5035 810);
FORCEPROP 2 LASTPIN (-5025 750) $PN AA56
J 2
(-5035 760);
DISPLAY 0.617021 (-5035 760);
PAINT ORANGE (-5035 760);
FORCEPROP 2 LASTPIN (-5025 700) $PN W54
J 2
(-5035 710);
DISPLAY 0.617021 (-5035 710);
PAINT ORANGE (-5035 710);
FORCEPROP 2 LASTPIN (-5025 650) $PN AA54
J 2
(-5035 660);
DISPLAY 0.617021 (-5035 660);
PAINT ORANGE (-5035 660);
FORCEPROP 2 LASTPIN (-3325 1850) $PN AB63
J 0
(-3315 1860);
DISPLAY 0.617021 (-3315 1860);
PAINT ORANGE (-3315 1860);
FORCEPROP 2 LASTPIN (-3325 1800) $PN V63
J 0
(-3315 1810);
DISPLAY 0.617021 (-3315 1810);
PAINT ORANGE (-3315 1810);
FORCEPROP 2 LASTPIN (-3325 1750) $PN AD63
J 0
(-3315 1760);
DISPLAY 0.617021 (-3315 1760);
PAINT ORANGE (-3315 1760);
FORCEPROP 2 LASTPIN (-3325 1700) $PN AA62
J 0
(-3315 1710);
DISPLAY 0.617021 (-3315 1710);
PAINT ORANGE (-3315 1710);
FORCEPROP 2 LASTPIN (-5025 550) $PN AB45
J 2
(-5035 560);
DISPLAY 0.617021 (-5035 560);
PAINT ORANGE (-5035 560);
FORCEPROP 2 LASTPIN (-3325 900) $PN AE62
J 0
(-3315 910);
DISPLAY 0.617021 (-3315 910);
PAINT ORANGE (-3315 910);
FORCEPROP 2 LASTPIN (-3325 850) $PN AA60
J 0
(-3315 860);
DISPLAY 0.617021 (-3315 860);
PAINT ORANGE (-3315 860);
FORCEPROP 2 LASTPIN (-3325 800) $PN AE56
J 0
(-3315 810);
DISPLAY 0.617021 (-3315 810);
PAINT ORANGE (-3315 810);
FORCEPROP 2 LASTPIN (-3325 750) $PN W52
J 0
(-3315 760);
DISPLAY 0.617021 (-3315 760);
PAINT ORANGE (-3315 760);
FORCEPROP 2 LASTPIN (-3325 600) $PN AD61
J 0
(-3315 610);
DISPLAY 0.617021 (-3315 610);
PAINT ORANGE (-3315 610);
FORCEPROP 2 LASTPIN (-3325 650) $PN AB61
J 0
(-3315 660);
DISPLAY 0.617021 (-3315 660);
PAINT ORANGE (-3315 660);
FORCEPROP 1 LAST PACK_TYPE BGA1
J 0
(-4975 5000);
PAINT SKYBLUE (-4975 5000);
DISPLAY INVISIBLE (-4975 5000);
FORCEPROP 2 LAST CDS_LIB chpset_lib
J 0
(-4175 2600);
PAINT ORANGE (-4175 2600);
DISPLAY INVISIBLE (-4175 2600);
FORCEPROP 2 LAST SEC_TYPE BGA1
J 0
(-4975 5000);
DISPLAY 1.021277 (-4975 5000);
PAINT ORANGE (-4975 5000);
DISPLAY INVISIBLE (-4975 5000);
FORCEPROP 2 LAST SEC 5
J 0
(-4975 5000);
DISPLAY 0.680851 (-4975 5000);
PAINT MONO (-4975 5000);
DISPLAY INVISIBLE (-4975 5000);
FORCEPROP 2 LAST CDS_LOCATION U5D1
J 0
(-4975 4950);
DISPLAY 0.617021 (-4975 4950);
PAINT AQUA (-4975 4950);
DISPLAY INVISIBLE (-4975 4950);
FORCEPROP 1 LAST PATH I172
J 0
(-4175 4900);
PAINT GREEN (-4175 4900);
DISPLAY INVISIBLE (-4175 4900);
FORCEPROP 0 LAST ROOM CPU0
J 0
(-4975 5050);
DISPLAY 1.021277 (-4975 5050);
PAINT ORANGE (-4975 5050);
DISPLAY INVISIBLE (-4975 5050);
FORCEADD TAP..6
(-5575 1350);
FORCEPROP 3 LASTPIN (-5525 1350) SIG_NAME M_C_ECC<5>
J 0
(-5515 1360);
DISPLAY 0.659574 (-5515 1360);
PAINT MONO (-5515 1360);
DISPLAY INVISIBLE (-5515 1360);
FORCEPROP 1 LASTPIN (-5525 1350) BN 5
J 0
(-5577 1358);
DISPLAY 0.617021 (-5577 1358);
PAINT PINK (-5577 1358);
FORCEPROP 2 LAST CDS_LIB mstr_standard
J 0
(-5575 1350);
PAINT MONO (-5575 1350);
DISPLAY INVISIBLE (-5575 1350);
FORCEPROP 1 LAST BODY_TYPE PLUMBING
J 0
(-5575 1300);
DISPLAY 1.595745 (-5575 1300);
PAINT GREEN (-5575 1300);
DISPLAY INVISIBLE (-5575 1300);
FORCEPROP 1 LAST HDL_TAP TRUE
J 0
(-5250 1225);
DISPLAY 1.595745 (-5250 1225);
PAINT GREEN (-5250 1225);
DISPLAY INVISIBLE (-5250 1225);
FORCEPROP 1 LAST PATH I18
J 0
(-5577 1350);
DISPLAY 0.872340 (-5577 1350);
PAINT GREEN (-5577 1350);
DISPLAY INVISIBLE (-5577 1350);
FORCEADD TAP..6
(-5575 1400);
FORCEPROP 3 LASTPIN (-5525 1400) SIG_NAME M_C_ECC<6>
J 0
(-5515 1410);
DISPLAY 0.659574 (-5515 1410);
PAINT MONO (-5515 1410);
DISPLAY INVISIBLE (-5515 1410);
FORCEPROP 1 LASTPIN (-5525 1400) BN 6
J 0
(-5577 1408);
DISPLAY 0.617021 (-5577 1408);
PAINT PINK (-5577 1408);
FORCEPROP 2 LAST CDS_LIB mstr_standard
J 0
(-5575 1400);
PAINT MONO (-5575 1400);
DISPLAY INVISIBLE (-5575 1400);
FORCEPROP 1 LAST BODY_TYPE PLUMBING
J 0
(-5575 1350);
DISPLAY 1.595745 (-5575 1350);
PAINT GREEN (-5575 1350);
DISPLAY INVISIBLE (-5575 1350);
FORCEPROP 1 LAST HDL_TAP TRUE
J 0
(-5250 1275);
DISPLAY 1.595745 (-5250 1275);
PAINT GREEN (-5250 1275);
DISPLAY INVISIBLE (-5250 1275);
FORCEPROP 1 LAST PATH I19
J 0
(-5577 1400);
DISPLAY 0.872340 (-5577 1400);
PAINT GREEN (-5577 1400);
DISPLAY INVISIBLE (-5577 1400);
FORCEADD OFFPAGE..5
(-6425 850);
FORCEPROP 2 LAST $XR0 47 
J 0
(-6679 850);
DISPLAY 0.638298 (-6679 850);
PAINT MONO (-6679 850);
FORCEPROP 2 LAST $XR1 48 
J 0
(-6769 850);
DISPLAY 0.638298 (-6769 850);
PAINT MONO (-6769 850);
FORCEPROP 2 LAST CDS_LIB mstr_standard
J 0
(-6425 850);
PAINT MONO (-6425 850);
DISPLAY INVISIBLE (-6425 850);
FORCEPROP 1 LAST OFFPAGE TRUE
J 0
(-6100 725);
DISPLAY 1.170213 (-6100 725);
PAINT GREEN (-6100 725);
DISPLAY INVISIBLE (-6100 725);
FORCEPROP 1 LAST COMMENT_BODY TRUE
J 0
(-6325 775);
DISPLAY 1.170213 (-6325 775);
PAINT GREEN (-6325 775);
DISPLAY INVISIBLE (-6325 775);
FORCEPROP 2 LAST PATH I2
J 0
(-6375 925);
DISPLAY 1.021277 (-6375 925);
PAINT ORANGE (-6375 925);
DISPLAY INVISIBLE (-6375 925);
FORCEADD TAP..6
(-5575 1450);
FORCEPROP 3 LASTPIN (-5525 1450) SIG_NAME M_C_ECC<7>
J 0
(-5515 1460);
DISPLAY 0.659574 (-5515 1460);
PAINT MONO (-5515 1460);
DISPLAY INVISIBLE (-5515 1460);
FORCEPROP 1 LASTPIN (-5525 1450) BN 7
J 0
(-5577 1458);
DISPLAY 0.617021 (-5577 1458);
PAINT PINK (-5577 1458);
FORCEPROP 2 LAST CDS_LIB mstr_standard
J 0
(-5575 1450);
PAINT MONO (-5575 1450);
DISPLAY INVISIBLE (-5575 1450);
FORCEPROP 1 LAST BODY_TYPE PLUMBING
J 0
(-5575 1400);
DISPLAY 1.595745 (-5575 1400);
PAINT GREEN (-5575 1400);
DISPLAY INVISIBLE (-5575 1400);
FORCEPROP 1 LAST HDL_TAP TRUE
J 0
(-5250 1325);
DISPLAY 1.595745 (-5250 1325);
PAINT GREEN (-5250 1325);
DISPLAY INVISIBLE (-5250 1325);
FORCEPROP 1 LAST PATH I20
J 0
(-5577 1450);
DISPLAY 0.872340 (-5577 1450);
PAINT GREEN (-5577 1450);
DISPLAY INVISIBLE (-5577 1450);
FORCEADD TAP..6
(-5575 1600);
FORCEPROP 3 LASTPIN (-5525 1600) SIG_NAME M_C_DQ<1>
J 0
(-5515 1610);
DISPLAY 0.659574 (-5515 1610);
PAINT MONO (-5515 1610);
DISPLAY INVISIBLE (-5515 1610);
FORCEPROP 1 LASTPIN (-5525 1600) BN 1
J 0
(-5577 1608);
DISPLAY 0.617021 (-5577 1608);
PAINT PINK (-5577 1608);
FORCEPROP 2 LAST CDS_LIB mstr_standard
J 0
(-5575 1600);
PAINT MONO (-5575 1600);
DISPLAY INVISIBLE (-5575 1600);
FORCEPROP 1 LAST BODY_TYPE PLUMBING
J 0
(-5575 1550);
DISPLAY 1.595745 (-5575 1550);
PAINT GREEN (-5575 1550);
DISPLAY INVISIBLE (-5575 1550);
FORCEPROP 1 LAST HDL_TAP TRUE
J 0
(-5250 1475);
DISPLAY 1.595745 (-5250 1475);
PAINT GREEN (-5250 1475);
DISPLAY INVISIBLE (-5250 1475);
FORCEPROP 1 LAST PATH I21
J 0
(-5577 1600);
DISPLAY 0.872340 (-5577 1600);
PAINT GREEN (-5577 1600);
DISPLAY INVISIBLE (-5577 1600);
FORCEADD TAP..6
(-5575 1550);
FORCEPROP 3 LASTPIN (-5525 1550) SIG_NAME M_C_DQ<0>
J 0
(-5515 1560);
DISPLAY 0.659574 (-5515 1560);
PAINT MONO (-5515 1560);
DISPLAY INVISIBLE (-5515 1560);
FORCEPROP 1 LASTPIN (-5525 1550) BN 0
J 0
(-5577 1558);
DISPLAY 0.617021 (-5577 1558);
PAINT PINK (-5577 1558);
FORCEPROP 2 LAST CDS_LIB mstr_standard
J 0
(-5575 1550);
PAINT MONO (-5575 1550);
DISPLAY INVISIBLE (-5575 1550);
FORCEPROP 1 LAST BODY_TYPE PLUMBING
J 0
(-5575 1500);
DISPLAY 1.595745 (-5575 1500);
PAINT GREEN (-5575 1500);
DISPLAY INVISIBLE (-5575 1500);
FORCEPROP 1 LAST HDL_TAP TRUE
J 0
(-5250 1425);
DISPLAY 1.595745 (-5250 1425);
PAINT GREEN (-5250 1425);
DISPLAY INVISIBLE (-5250 1425);
FORCEPROP 1 LAST PATH I22
J 0
(-5577 1550);
DISPLAY 0.872340 (-5577 1550);
PAINT GREEN (-5577 1550);
DISPLAY INVISIBLE (-5577 1550);
FORCEADD TAP..6
(-5575 1650);
FORCEPROP 3 LASTPIN (-5525 1650) SIG_NAME M_C_DQ<2>
J 0
(-5515 1660);
DISPLAY 0.659574 (-5515 1660);
PAINT MONO (-5515 1660);
DISPLAY INVISIBLE (-5515 1660);
FORCEPROP 1 LASTPIN (-5525 1650) BN 2
J 0
(-5577 1658);
DISPLAY 0.617021 (-5577 1658);
PAINT PINK (-5577 1658);
FORCEPROP 2 LAST CDS_LIB mstr_standard
J 0
(-5575 1650);
PAINT MONO (-5575 1650);
DISPLAY INVISIBLE (-5575 1650);
FORCEPROP 1 LAST BODY_TYPE PLUMBING
J 0
(-5575 1600);
DISPLAY 1.595745 (-5575 1600);
PAINT GREEN (-5575 1600);
DISPLAY INVISIBLE (-5575 1600);
FORCEPROP 1 LAST HDL_TAP TRUE
J 0
(-5250 1525);
DISPLAY 1.595745 (-5250 1525);
PAINT GREEN (-5250 1525);
DISPLAY INVISIBLE (-5250 1525);
FORCEPROP 1 LAST PATH I23
J 0
(-5577 1650);
DISPLAY 0.872340 (-5577 1650);
PAINT GREEN (-5577 1650);
DISPLAY INVISIBLE (-5577 1650);
FORCEADD TAP..6
(-5575 1700);
FORCEPROP 3 LASTPIN (-5525 1700) SIG_NAME M_C_DQ<3>
J 0
(-5515 1710);
DISPLAY 0.659574 (-5515 1710);
PAINT MONO (-5515 1710);
DISPLAY INVISIBLE (-5515 1710);
FORCEPROP 1 LASTPIN (-5525 1700) BN 3
J 0
(-5577 1708);
DISPLAY 0.617021 (-5577 1708);
PAINT PINK (-5577 1708);
FORCEPROP 2 LAST CDS_LIB mstr_standard
J 0
(-5575 1700);
PAINT MONO (-5575 1700);
DISPLAY INVISIBLE (-5575 1700);
FORCEPROP 1 LAST BODY_TYPE PLUMBING
J 0
(-5575 1650);
DISPLAY 1.595745 (-5575 1650);
PAINT GREEN (-5575 1650);
DISPLAY INVISIBLE (-5575 1650);
FORCEPROP 1 LAST HDL_TAP TRUE
J 0
(-5250 1575);
DISPLAY 1.595745 (-5250 1575);
PAINT GREEN (-5250 1575);
DISPLAY INVISIBLE (-5250 1575);
FORCEPROP 1 LAST PATH I24
J 0
(-5577 1700);
DISPLAY 0.872340 (-5577 1700);
PAINT GREEN (-5577 1700);
DISPLAY INVISIBLE (-5577 1700);
FORCEADD TAP..6
(-5575 1750);
FORCEPROP 3 LASTPIN (-5525 1750) SIG_NAME M_C_DQ<4>
J 0
(-5515 1760);
DISPLAY 0.659574 (-5515 1760);
PAINT MONO (-5515 1760);
DISPLAY INVISIBLE (-5515 1760);
FORCEPROP 1 LASTPIN (-5525 1750) BN 4
J 0
(-5577 1758);
DISPLAY 0.617021 (-5577 1758);
PAINT PINK (-5577 1758);
FORCEPROP 2 LAST CDS_LIB mstr_standard
J 0
(-5575 1750);
PAINT MONO (-5575 1750);
DISPLAY INVISIBLE (-5575 1750);
FORCEPROP 1 LAST BODY_TYPE PLUMBING
J 0
(-5575 1700);
DISPLAY 1.595745 (-5575 1700);
PAINT GREEN (-5575 1700);
DISPLAY INVISIBLE (-5575 1700);
FORCEPROP 1 LAST HDL_TAP TRUE
J 0
(-5250 1625);
DISPLAY 1.595745 (-5250 1625);
PAINT GREEN (-5250 1625);
DISPLAY INVISIBLE (-5250 1625);
FORCEPROP 1 LAST PATH I25
J 0
(-5577 1750);
DISPLAY 0.872340 (-5577 1750);
PAINT GREEN (-5577 1750);
DISPLAY INVISIBLE (-5577 1750);
FORCEADD TAP..6
(-5575 1800);
FORCEPROP 3 LASTPIN (-5525 1800) SIG_NAME M_C_DQ<5>
J 0
(-5515 1810);
DISPLAY 0.659574 (-5515 1810);
PAINT MONO (-5515 1810);
DISPLAY INVISIBLE (-5515 1810);
FORCEPROP 1 LASTPIN (-5525 1800) BN 5
J 0
(-5577 1808);
DISPLAY 0.617021 (-5577 1808);
PAINT PINK (-5577 1808);
FORCEPROP 2 LAST CDS_LIB mstr_standard
J 0
(-5575 1800);
PAINT MONO (-5575 1800);
DISPLAY INVISIBLE (-5575 1800);
FORCEPROP 1 LAST BODY_TYPE PLUMBING
J 0
(-5575 1750);
DISPLAY 1.595745 (-5575 1750);
PAINT GREEN (-5575 1750);
DISPLAY INVISIBLE (-5575 1750);
FORCEPROP 1 LAST HDL_TAP TRUE
J 0
(-5250 1675);
DISPLAY 1.595745 (-5250 1675);
PAINT GREEN (-5250 1675);
DISPLAY INVISIBLE (-5250 1675);
FORCEPROP 1 LAST PATH I26
J 0
(-5577 1800);
DISPLAY 0.872340 (-5577 1800);
PAINT GREEN (-5577 1800);
DISPLAY INVISIBLE (-5577 1800);
FORCEADD TAP..6
(-5575 1850);
FORCEPROP 3 LASTPIN (-5525 1850) SIG_NAME M_C_DQ<6>
J 0
(-5515 1860);
DISPLAY 0.659574 (-5515 1860);
PAINT MONO (-5515 1860);
DISPLAY INVISIBLE (-5515 1860);
FORCEPROP 1 LASTPIN (-5525 1850) BN 6
J 0
(-5577 1858);
DISPLAY 0.617021 (-5577 1858);
PAINT PINK (-5577 1858);
FORCEPROP 2 LAST CDS_LIB mstr_standard
J 0
(-5575 1850);
PAINT MONO (-5575 1850);
DISPLAY INVISIBLE (-5575 1850);
FORCEPROP 1 LAST BODY_TYPE PLUMBING
J 0
(-5575 1800);
DISPLAY 1.595745 (-5575 1800);
PAINT GREEN (-5575 1800);
DISPLAY INVISIBLE (-5575 1800);
FORCEPROP 1 LAST HDL_TAP TRUE
J 0
(-5250 1725);
DISPLAY 1.595745 (-5250 1725);
PAINT GREEN (-5250 1725);
DISPLAY INVISIBLE (-5250 1725);
FORCEPROP 1 LAST PATH I27
J 0
(-5577 1850);
DISPLAY 0.872340 (-5577 1850);
PAINT GREEN (-5577 1850);
DISPLAY INVISIBLE (-5577 1850);
FORCEADD TAP..6
(-5575 1900);
FORCEPROP 3 LASTPIN (-5525 1900) SIG_NAME M_C_DQ<7>
J 0
(-5515 1910);
DISPLAY 0.659574 (-5515 1910);
PAINT MONO (-5515 1910);
DISPLAY INVISIBLE (-5515 1910);
FORCEPROP 1 LASTPIN (-5525 1900) BN 7
J 0
(-5577 1908);
DISPLAY 0.617021 (-5577 1908);
PAINT PINK (-5577 1908);
FORCEPROP 2 LAST CDS_LIB mstr_standard
J 0
(-5575 1900);
PAINT MONO (-5575 1900);
DISPLAY INVISIBLE (-5575 1900);
FORCEPROP 1 LAST BODY_TYPE PLUMBING
J 0
(-5575 1850);
DISPLAY 1.595745 (-5575 1850);
PAINT GREEN (-5575 1850);
DISPLAY INVISIBLE (-5575 1850);
FORCEPROP 1 LAST HDL_TAP TRUE
J 0
(-5250 1775);
DISPLAY 1.595745 (-5250 1775);
PAINT GREEN (-5250 1775);
DISPLAY INVISIBLE (-5250 1775);
FORCEPROP 1 LAST PATH I28
J 0
(-5577 1900);
DISPLAY 0.872340 (-5577 1900);
PAINT GREEN (-5577 1900);
DISPLAY INVISIBLE (-5577 1900);
FORCEADD TAP..6
(-5575 1950);
FORCEPROP 3 LASTPIN (-5525 1950) SIG_NAME M_C_DQ<8>
J 0
(-5515 1960);
DISPLAY 0.659574 (-5515 1960);
PAINT MONO (-5515 1960);
DISPLAY INVISIBLE (-5515 1960);
FORCEPROP 1 LASTPIN (-5525 1950) BN 8
J 0
(-5577 1958);
DISPLAY 0.617021 (-5577 1958);
PAINT PINK (-5577 1958);
FORCEPROP 2 LAST CDS_LIB mstr_standard
J 0
(-5575 1950);
PAINT MONO (-5575 1950);
DISPLAY INVISIBLE (-5575 1950);
FORCEPROP 1 LAST BODY_TYPE PLUMBING
J 0
(-5575 1900);
DISPLAY 1.595745 (-5575 1900);
PAINT GREEN (-5575 1900);
DISPLAY INVISIBLE (-5575 1900);
FORCEPROP 1 LAST HDL_TAP TRUE
J 0
(-5250 1825);
DISPLAY 1.595745 (-5250 1825);
PAINT GREEN (-5250 1825);
DISPLAY INVISIBLE (-5250 1825);
FORCEPROP 1 LAST PATH I29
J 0
(-5577 1950);
DISPLAY 0.872340 (-5577 1950);
PAINT GREEN (-5577 1950);
DISPLAY INVISIBLE (-5577 1950);
FORCEADD OFFPAGE..5
(-6425 1050);
FORCEPROP 2 LAST $XR0 47 
J 0
(-6679 1050);
DISPLAY 0.638298 (-6679 1050);
PAINT MONO (-6679 1050);
FORCEPROP 2 LAST $XR1 48 
J 0
(-6769 1050);
DISPLAY 0.638298 (-6769 1050);
PAINT MONO (-6769 1050);
FORCEPROP 2 LAST CDS_LIB mstr_standard
J 0
(-6425 1050);
PAINT MONO (-6425 1050);
DISPLAY INVISIBLE (-6425 1050);
FORCEPROP 1 LAST OFFPAGE TRUE
J 0
(-6100 925);
DISPLAY 1.170213 (-6100 925);
PAINT GREEN (-6100 925);
DISPLAY INVISIBLE (-6100 925);
FORCEPROP 1 LAST COMMENT_BODY TRUE
J 0
(-6325 975);
DISPLAY 1.170213 (-6325 975);
PAINT GREEN (-6325 975);
DISPLAY INVISIBLE (-6325 975);
FORCEPROP 2 LAST PATH I3
J 0
(-6375 1125);
DISPLAY 1.021277 (-6375 1125);
PAINT ORANGE (-6375 1125);
DISPLAY INVISIBLE (-6375 1125);
FORCEADD TAP..6
(-5575 2100);
FORCEPROP 3 LASTPIN (-5525 2100) SIG_NAME M_C_DQ<11>
J 0
(-5515 2110);
DISPLAY 0.659574 (-5515 2110);
PAINT MONO (-5515 2110);
DISPLAY INVISIBLE (-5515 2110);
FORCEPROP 1 LASTPIN (-5525 2100) BN 11
J 0
(-5577 2108);
DISPLAY 0.617021 (-5577 2108);
PAINT PINK (-5577 2108);
FORCEPROP 2 LAST CDS_LIB mstr_standard
J 0
(-5575 2100);
PAINT MONO (-5575 2100);
DISPLAY INVISIBLE (-5575 2100);
FORCEPROP 1 LAST BODY_TYPE PLUMBING
J 0
(-5575 2050);
DISPLAY 1.595745 (-5575 2050);
PAINT GREEN (-5575 2050);
DISPLAY INVISIBLE (-5575 2050);
FORCEPROP 1 LAST HDL_TAP TRUE
J 0
(-5250 1975);
DISPLAY 1.595745 (-5250 1975);
PAINT GREEN (-5250 1975);
DISPLAY INVISIBLE (-5250 1975);
FORCEPROP 1 LAST PATH I31
J 0
(-5577 2100);
DISPLAY 0.872340 (-5577 2100);
PAINT GREEN (-5577 2100);
DISPLAY INVISIBLE (-5577 2100);
FORCEADD TAP..6
(-5575 2050);
FORCEPROP 3 LASTPIN (-5525 2050) SIG_NAME M_C_DQ<10>
J 0
(-5515 2060);
DISPLAY 0.659574 (-5515 2060);
PAINT MONO (-5515 2060);
DISPLAY INVISIBLE (-5515 2060);
FORCEPROP 1 LASTPIN (-5525 2050) BN 10
J 0
(-5577 2058);
DISPLAY 0.617021 (-5577 2058);
PAINT PINK (-5577 2058);
FORCEPROP 2 LAST CDS_LIB mstr_standard
J 0
(-5575 2050);
PAINT MONO (-5575 2050);
DISPLAY INVISIBLE (-5575 2050);
FORCEPROP 1 LAST BODY_TYPE PLUMBING
J 0
(-5575 2000);
DISPLAY 1.595745 (-5575 2000);
PAINT GREEN (-5575 2000);
DISPLAY INVISIBLE (-5575 2000);
FORCEPROP 1 LAST HDL_TAP TRUE
J 0
(-5250 1925);
DISPLAY 1.595745 (-5250 1925);
PAINT GREEN (-5250 1925);
DISPLAY INVISIBLE (-5250 1925);
FORCEPROP 1 LAST PATH I32
J 0
(-5577 2050);
DISPLAY 0.872340 (-5577 2050);
PAINT GREEN (-5577 2050);
DISPLAY INVISIBLE (-5577 2050);
FORCEADD TAP..6
(-5575 2000);
FORCEPROP 3 LASTPIN (-5525 2000) SIG_NAME M_C_DQ<9>
J 0
(-5515 2010);
DISPLAY 0.659574 (-5515 2010);
PAINT MONO (-5515 2010);
DISPLAY INVISIBLE (-5515 2010);
FORCEPROP 1 LASTPIN (-5525 2000) BN 9
J 0
(-5577 2008);
DISPLAY 0.617021 (-5577 2008);
PAINT PINK (-5577 2008);
FORCEPROP 2 LAST CDS_LIB mstr_standard
J 0
(-5575 2000);
PAINT MONO (-5575 2000);
DISPLAY INVISIBLE (-5575 2000);
FORCEPROP 1 LAST BODY_TYPE PLUMBING
J 0
(-5575 1950);
DISPLAY 1.595745 (-5575 1950);
PAINT GREEN (-5575 1950);
DISPLAY INVISIBLE (-5575 1950);
FORCEPROP 1 LAST HDL_TAP TRUE
J 0
(-5250 1875);
DISPLAY 1.595745 (-5250 1875);
PAINT GREEN (-5250 1875);
DISPLAY INVISIBLE (-5250 1875);
FORCEPROP 1 LAST PATH I33
J 0
(-5577 2000);
DISPLAY 0.872340 (-5577 2000);
PAINT GREEN (-5577 2000);
DISPLAY INVISIBLE (-5577 2000);
FORCEADD TAP..6
(-5575 2150);
FORCEPROP 3 LASTPIN (-5525 2150) SIG_NAME M_C_DQ<12>
J 0
(-5515 2160);
DISPLAY 0.659574 (-5515 2160);
PAINT MONO (-5515 2160);
DISPLAY INVISIBLE (-5515 2160);
FORCEPROP 1 LASTPIN (-5525 2150) BN 12
J 0
(-5577 2158);
DISPLAY 0.617021 (-5577 2158);
PAINT PINK (-5577 2158);
FORCEPROP 2 LAST CDS_LIB mstr_standard
J 0
(-5575 2150);
PAINT MONO (-5575 2150);
DISPLAY INVISIBLE (-5575 2150);
FORCEPROP 1 LAST BODY_TYPE PLUMBING
J 0
(-5575 2100);
DISPLAY 1.595745 (-5575 2100);
PAINT GREEN (-5575 2100);
DISPLAY INVISIBLE (-5575 2100);
FORCEPROP 1 LAST HDL_TAP TRUE
J 0
(-5250 2025);
DISPLAY 1.595745 (-5250 2025);
PAINT GREEN (-5250 2025);
DISPLAY INVISIBLE (-5250 2025);
FORCEPROP 1 LAST PATH I34
J 0
(-5577 2150);
DISPLAY 0.872340 (-5577 2150);
PAINT GREEN (-5577 2150);
DISPLAY INVISIBLE (-5577 2150);
FORCEADD TAP..6
(-5575 2200);
FORCEPROP 3 LASTPIN (-5525 2200) SIG_NAME M_C_DQ<13>
J 0
(-5515 2210);
DISPLAY 0.659574 (-5515 2210);
PAINT MONO (-5515 2210);
DISPLAY INVISIBLE (-5515 2210);
FORCEPROP 1 LASTPIN (-5525 2200) BN 13
J 0
(-5577 2208);
DISPLAY 0.617021 (-5577 2208);
PAINT PINK (-5577 2208);
FORCEPROP 2 LAST CDS_LIB mstr_standard
J 0
(-5575 2200);
PAINT MONO (-5575 2200);
DISPLAY INVISIBLE (-5575 2200);
FORCEPROP 1 LAST BODY_TYPE PLUMBING
J 0
(-5575 2150);
DISPLAY 1.595745 (-5575 2150);
PAINT GREEN (-5575 2150);
DISPLAY INVISIBLE (-5575 2150);
FORCEPROP 1 LAST HDL_TAP TRUE
J 0
(-5250 2075);
DISPLAY 1.595745 (-5250 2075);
PAINT GREEN (-5250 2075);
DISPLAY INVISIBLE (-5250 2075);
FORCEPROP 1 LAST PATH I35
J 0
(-5577 2200);
DISPLAY 0.872340 (-5577 2200);
PAINT GREEN (-5577 2200);
DISPLAY INVISIBLE (-5577 2200);
FORCEADD TAP..6
(-5575 2250);
FORCEPROP 3 LASTPIN (-5525 2250) SIG_NAME M_C_DQ<14>
J 0
(-5515 2260);
DISPLAY 0.659574 (-5515 2260);
PAINT MONO (-5515 2260);
DISPLAY INVISIBLE (-5515 2260);
FORCEPROP 1 LASTPIN (-5525 2250) BN 14
J 0
(-5577 2258);
DISPLAY 0.617021 (-5577 2258);
PAINT PINK (-5577 2258);
FORCEPROP 2 LAST CDS_LIB mstr_standard
J 0
(-5575 2250);
PAINT MONO (-5575 2250);
DISPLAY INVISIBLE (-5575 2250);
FORCEPROP 1 LAST BODY_TYPE PLUMBING
J 0
(-5575 2200);
DISPLAY 1.595745 (-5575 2200);
PAINT GREEN (-5575 2200);
DISPLAY INVISIBLE (-5575 2200);
FORCEPROP 1 LAST HDL_TAP TRUE
J 0
(-5250 2125);
DISPLAY 1.595745 (-5250 2125);
PAINT GREEN (-5250 2125);
DISPLAY INVISIBLE (-5250 2125);
FORCEPROP 1 LAST PATH I36
J 0
(-5577 2250);
DISPLAY 0.872340 (-5577 2250);
PAINT GREEN (-5577 2250);
DISPLAY INVISIBLE (-5577 2250);
FORCEADD TAP..6
(-5575 2300);
FORCEPROP 3 LASTPIN (-5525 2300) SIG_NAME M_C_DQ<15>
J 0
(-5515 2310);
DISPLAY 0.659574 (-5515 2310);
PAINT MONO (-5515 2310);
DISPLAY INVISIBLE (-5515 2310);
FORCEPROP 1 LASTPIN (-5525 2300) BN 15
J 0
(-5577 2308);
DISPLAY 0.617021 (-5577 2308);
PAINT PINK (-5577 2308);
FORCEPROP 2 LAST CDS_LIB mstr_standard
J 0
(-5575 2300);
PAINT MONO (-5575 2300);
DISPLAY INVISIBLE (-5575 2300);
FORCEPROP 1 LAST BODY_TYPE PLUMBING
J 0
(-5575 2250);
DISPLAY 1.595745 (-5575 2250);
PAINT GREEN (-5575 2250);
DISPLAY INVISIBLE (-5575 2250);
FORCEPROP 1 LAST HDL_TAP TRUE
J 0
(-5250 2175);
DISPLAY 1.595745 (-5250 2175);
PAINT GREEN (-5250 2175);
DISPLAY INVISIBLE (-5250 2175);
FORCEPROP 1 LAST PATH I37
J 0
(-5577 2300);
DISPLAY 0.872340 (-5577 2300);
PAINT GREEN (-5577 2300);
DISPLAY INVISIBLE (-5577 2300);
FORCEADD TAP..6
(-5575 2350);
FORCEPROP 3 LASTPIN (-5525 2350) SIG_NAME M_C_DQ<16>
J 0
(-5515 2360);
DISPLAY 0.659574 (-5515 2360);
PAINT MONO (-5515 2360);
DISPLAY INVISIBLE (-5515 2360);
FORCEPROP 1 LASTPIN (-5525 2350) BN 16
J 0
(-5577 2358);
DISPLAY 0.617021 (-5577 2358);
PAINT PINK (-5577 2358);
FORCEPROP 2 LAST CDS_LIB mstr_standard
J 0
(-5575 2350);
PAINT MONO (-5575 2350);
DISPLAY INVISIBLE (-5575 2350);
FORCEPROP 1 LAST BODY_TYPE PLUMBING
J 0
(-5575 2300);
DISPLAY 1.595745 (-5575 2300);
PAINT GREEN (-5575 2300);
DISPLAY INVISIBLE (-5575 2300);
FORCEPROP 1 LAST HDL_TAP TRUE
J 0
(-5250 2225);
DISPLAY 1.595745 (-5250 2225);
PAINT GREEN (-5250 2225);
DISPLAY INVISIBLE (-5250 2225);
FORCEPROP 1 LAST PATH I38
J 0
(-5577 2350);
DISPLAY 0.872340 (-5577 2350);
PAINT GREEN (-5577 2350);
DISPLAY INVISIBLE (-5577 2350);
FORCEADD TAP..6
(-5575 2400);
FORCEPROP 3 LASTPIN (-5525 2400) SIG_NAME M_C_DQ<17>
J 0
(-5515 2410);
DISPLAY 0.659574 (-5515 2410);
PAINT MONO (-5515 2410);
DISPLAY INVISIBLE (-5515 2410);
FORCEPROP 1 LASTPIN (-5525 2400) BN 17
J 0
(-5577 2408);
DISPLAY 0.617021 (-5577 2408);
PAINT PINK (-5577 2408);
FORCEPROP 2 LAST CDS_LIB mstr_standard
J 0
(-5575 2400);
PAINT MONO (-5575 2400);
DISPLAY INVISIBLE (-5575 2400);
FORCEPROP 1 LAST BODY_TYPE PLUMBING
J 0
(-5575 2350);
DISPLAY 1.595745 (-5575 2350);
PAINT GREEN (-5575 2350);
DISPLAY INVISIBLE (-5575 2350);
FORCEPROP 1 LAST HDL_TAP TRUE
J 0
(-5250 2275);
DISPLAY 1.595745 (-5250 2275);
PAINT GREEN (-5250 2275);
DISPLAY INVISIBLE (-5250 2275);
FORCEPROP 1 LAST PATH I39
J 0
(-5577 2400);
DISPLAY 0.872340 (-5577 2400);
PAINT GREEN (-5577 2400);
DISPLAY INVISIBLE (-5577 2400);
FORCEADD OFFPAGE..6
(-6425 1500);
FORCEPROP 2 LAST $XR0 47 
J 0
(-6674 1500);
DISPLAY 0.638298 (-6674 1500);
PAINT MONO (-6674 1500);
FORCEPROP 2 LAST $XR1 48 
J 0
(-6764 1500);
DISPLAY 0.638298 (-6764 1500);
PAINT MONO (-6764 1500);
FORCEPROP 2 LAST CDS_LIB mstr_standard
J 0
(-6425 1500);
PAINT MONO (-6425 1500);
DISPLAY INVISIBLE (-6425 1500);
FORCEPROP 1 LAST OFFPAGE TRUE
J 0
(-6100 1375);
DISPLAY 1.170213 (-6100 1375);
PAINT GREEN (-6100 1375);
DISPLAY INVISIBLE (-6100 1375);
FORCEPROP 1 LAST COMMENT_BODY TRUE
J 0
(-6325 1425);
DISPLAY 1.170213 (-6325 1425);
PAINT GREEN (-6325 1425);
DISPLAY INVISIBLE (-6325 1425);
FORCEPROP 2 LAST PATH I4
J 0
(-6375 1575);
DISPLAY 1.021277 (-6375 1575);
PAINT ORANGE (-6375 1575);
DISPLAY INVISIBLE (-6375 1575);
FORCEADD TAP..6
(-5575 2450);
FORCEPROP 3 LASTPIN (-5525 2450) SIG_NAME M_C_DQ<18>
J 0
(-5515 2460);
DISPLAY 0.659574 (-5515 2460);
PAINT MONO (-5515 2460);
DISPLAY INVISIBLE (-5515 2460);
FORCEPROP 1 LASTPIN (-5525 2450) BN 18
J 0
(-5577 2458);
DISPLAY 0.617021 (-5577 2458);
PAINT PINK (-5577 2458);
FORCEPROP 2 LAST CDS_LIB mstr_standard
J 0
(-5575 2450);
PAINT MONO (-5575 2450);
DISPLAY INVISIBLE (-5575 2450);
FORCEPROP 1 LAST BODY_TYPE PLUMBING
J 0
(-5575 2400);
DISPLAY 1.595745 (-5575 2400);
PAINT GREEN (-5575 2400);
DISPLAY INVISIBLE (-5575 2400);
FORCEPROP 1 LAST HDL_TAP TRUE
J 0
(-5250 2325);
DISPLAY 1.595745 (-5250 2325);
PAINT GREEN (-5250 2325);
DISPLAY INVISIBLE (-5250 2325);
FORCEPROP 1 LAST PATH I40
J 0
(-5577 2450);
DISPLAY 0.872340 (-5577 2450);
PAINT GREEN (-5577 2450);
DISPLAY INVISIBLE (-5577 2450);
FORCEADD TAP..6
(-5575 2500);
FORCEPROP 3 LASTPIN (-5525 2500) SIG_NAME M_C_DQ<19>
J 0
(-5515 2510);
DISPLAY 0.659574 (-5515 2510);
PAINT MONO (-5515 2510);
DISPLAY INVISIBLE (-5515 2510);
FORCEPROP 1 LASTPIN (-5525 2500) BN 19
J 0
(-5577 2508);
DISPLAY 0.617021 (-5577 2508);
PAINT PINK (-5577 2508);
FORCEPROP 2 LAST CDS_LIB mstr_standard
J 0
(-5575 2500);
PAINT MONO (-5575 2500);
DISPLAY INVISIBLE (-5575 2500);
FORCEPROP 1 LAST BODY_TYPE PLUMBING
J 0
(-5575 2450);
DISPLAY 1.595745 (-5575 2450);
PAINT GREEN (-5575 2450);
DISPLAY INVISIBLE (-5575 2450);
FORCEPROP 1 LAST HDL_TAP TRUE
J 0
(-5250 2375);
DISPLAY 1.595745 (-5250 2375);
PAINT GREEN (-5250 2375);
DISPLAY INVISIBLE (-5250 2375);
FORCEPROP 1 LAST PATH I41
J 0
(-5577 2500);
DISPLAY 0.872340 (-5577 2500);
PAINT GREEN (-5577 2500);
DISPLAY INVISIBLE (-5577 2500);
FORCEADD TAP..6
(-5575 2600);
FORCEPROP 3 LASTPIN (-5525 2600) SIG_NAME M_C_DQ<21>
J 0
(-5515 2610);
DISPLAY 0.659574 (-5515 2610);
PAINT MONO (-5515 2610);
DISPLAY INVISIBLE (-5515 2610);
FORCEPROP 1 LASTPIN (-5525 2600) BN 21
J 0
(-5577 2608);
DISPLAY 0.617021 (-5577 2608);
PAINT PINK (-5577 2608);
FORCEPROP 2 LAST CDS_LIB mstr_standard
J 0
(-5575 2600);
PAINT MONO (-5575 2600);
DISPLAY INVISIBLE (-5575 2600);
FORCEPROP 1 LAST BODY_TYPE PLUMBING
J 0
(-5575 2550);
DISPLAY 1.595745 (-5575 2550);
PAINT GREEN (-5575 2550);
DISPLAY INVISIBLE (-5575 2550);
FORCEPROP 1 LAST HDL_TAP TRUE
J 0
(-5250 2475);
DISPLAY 1.595745 (-5250 2475);
PAINT GREEN (-5250 2475);
DISPLAY INVISIBLE (-5250 2475);
FORCEPROP 1 LAST PATH I42
J 0
(-5577 2600);
DISPLAY 0.872340 (-5577 2600);
PAINT GREEN (-5577 2600);
DISPLAY INVISIBLE (-5577 2600);
FORCEADD TAP..6
(-5575 2550);
FORCEPROP 3 LASTPIN (-5525 2550) SIG_NAME M_C_DQ<20>
J 0
(-5515 2560);
DISPLAY 0.659574 (-5515 2560);
PAINT MONO (-5515 2560);
DISPLAY INVISIBLE (-5515 2560);
FORCEPROP 1 LASTPIN (-5525 2550) BN 20
J 0
(-5577 2558);
DISPLAY 0.617021 (-5577 2558);
PAINT PINK (-5577 2558);
FORCEPROP 2 LAST CDS_LIB mstr_standard
J 0
(-5575 2550);
PAINT MONO (-5575 2550);
DISPLAY INVISIBLE (-5575 2550);
FORCEPROP 1 LAST BODY_TYPE PLUMBING
J 0
(-5575 2500);
DISPLAY 1.595745 (-5575 2500);
PAINT GREEN (-5575 2500);
DISPLAY INVISIBLE (-5575 2500);
FORCEPROP 1 LAST HDL_TAP TRUE
J 0
(-5250 2425);
DISPLAY 1.595745 (-5250 2425);
PAINT GREEN (-5250 2425);
DISPLAY INVISIBLE (-5250 2425);
FORCEPROP 1 LAST PATH I43
J 0
(-5577 2550);
DISPLAY 0.872340 (-5577 2550);
PAINT GREEN (-5577 2550);
DISPLAY INVISIBLE (-5577 2550);
FORCEADD TAP..6
(-5575 2650);
FORCEPROP 3 LASTPIN (-5525 2650) SIG_NAME M_C_DQ<22>
J 0
(-5515 2660);
DISPLAY 0.659574 (-5515 2660);
PAINT MONO (-5515 2660);
DISPLAY INVISIBLE (-5515 2660);
FORCEPROP 1 LASTPIN (-5525 2650) BN 22
J 0
(-5577 2658);
DISPLAY 0.617021 (-5577 2658);
PAINT PINK (-5577 2658);
FORCEPROP 2 LAST CDS_LIB mstr_standard
J 0
(-5575 2650);
PAINT MONO (-5575 2650);
DISPLAY INVISIBLE (-5575 2650);
FORCEPROP 1 LAST BODY_TYPE PLUMBING
J 0
(-5575 2600);
DISPLAY 1.595745 (-5575 2600);
PAINT GREEN (-5575 2600);
DISPLAY INVISIBLE (-5575 2600);
FORCEPROP 1 LAST HDL_TAP TRUE
J 0
(-5250 2525);
DISPLAY 1.595745 (-5250 2525);
PAINT GREEN (-5250 2525);
DISPLAY INVISIBLE (-5250 2525);
FORCEPROP 1 LAST PATH I44
J 0
(-5577 2650);
DISPLAY 0.872340 (-5577 2650);
PAINT GREEN (-5577 2650);
DISPLAY INVISIBLE (-5577 2650);
FORCEADD TAP..6
(-5575 2700);
FORCEPROP 3 LASTPIN (-5525 2700) SIG_NAME M_C_DQ<23>
J 0
(-5515 2710);
DISPLAY 0.659574 (-5515 2710);
PAINT MONO (-5515 2710);
DISPLAY INVISIBLE (-5515 2710);
FORCEPROP 1 LASTPIN (-5525 2700) BN 23
J 0
(-5577 2708);
DISPLAY 0.617021 (-5577 2708);
PAINT PINK (-5577 2708);
FORCEPROP 2 LAST CDS_LIB mstr_standard
J 0
(-5575 2700);
PAINT MONO (-5575 2700);
DISPLAY INVISIBLE (-5575 2700);
FORCEPROP 1 LAST BODY_TYPE PLUMBING
J 0
(-5575 2650);
DISPLAY 1.595745 (-5575 2650);
PAINT GREEN (-5575 2650);
DISPLAY INVISIBLE (-5575 2650);
FORCEPROP 1 LAST HDL_TAP TRUE
J 0
(-5250 2575);
DISPLAY 1.595745 (-5250 2575);
PAINT GREEN (-5250 2575);
DISPLAY INVISIBLE (-5250 2575);
FORCEPROP 1 LAST PATH I45
J 0
(-5577 2700);
DISPLAY 0.872340 (-5577 2700);
PAINT GREEN (-5577 2700);
DISPLAY INVISIBLE (-5577 2700);
FORCEADD TAP..6
(-5575 2750);
FORCEPROP 3 LASTPIN (-5525 2750) SIG_NAME M_C_DQ<24>
J 0
(-5515 2760);
DISPLAY 0.659574 (-5515 2760);
PAINT MONO (-5515 2760);
DISPLAY INVISIBLE (-5515 2760);
FORCEPROP 1 LASTPIN (-5525 2750) BN 24
J 0
(-5577 2758);
DISPLAY 0.617021 (-5577 2758);
PAINT PINK (-5577 2758);
FORCEPROP 2 LAST CDS_LIB mstr_standard
J 0
(-5575 2750);
PAINT MONO (-5575 2750);
DISPLAY INVISIBLE (-5575 2750);
FORCEPROP 1 LAST BODY_TYPE PLUMBING
J 0
(-5575 2700);
DISPLAY 1.595745 (-5575 2700);
PAINT GREEN (-5575 2700);
DISPLAY INVISIBLE (-5575 2700);
FORCEPROP 1 LAST HDL_TAP TRUE
J 0
(-5250 2625);
DISPLAY 1.595745 (-5250 2625);
PAINT GREEN (-5250 2625);
DISPLAY INVISIBLE (-5250 2625);
FORCEPROP 1 LAST PATH I46
J 0
(-5577 2750);
DISPLAY 0.872340 (-5577 2750);
PAINT GREEN (-5577 2750);
DISPLAY INVISIBLE (-5577 2750);
FORCEADD TAP..6
(-5575 2850);
FORCEPROP 3 LASTPIN (-5525 2850) SIG_NAME M_C_DQ<26>
J 0
(-5515 2860);
DISPLAY 0.659574 (-5515 2860);
PAINT MONO (-5515 2860);
DISPLAY INVISIBLE (-5515 2860);
FORCEPROP 1 LASTPIN (-5525 2850) BN 26
J 0
(-5577 2858);
DISPLAY 0.617021 (-5577 2858);
PAINT PINK (-5577 2858);
FORCEPROP 2 LAST CDS_LIB mstr_standard
J 0
(-5575 2850);
PAINT MONO (-5575 2850);
DISPLAY INVISIBLE (-5575 2850);
FORCEPROP 1 LAST BODY_TYPE PLUMBING
J 0
(-5575 2800);
DISPLAY 1.595745 (-5575 2800);
PAINT GREEN (-5575 2800);
DISPLAY INVISIBLE (-5575 2800);
FORCEPROP 1 LAST HDL_TAP TRUE
J 0
(-5250 2725);
DISPLAY 1.595745 (-5250 2725);
PAINT GREEN (-5250 2725);
DISPLAY INVISIBLE (-5250 2725);
FORCEPROP 1 LAST PATH I47
J 0
(-5577 2850);
DISPLAY 0.872340 (-5577 2850);
PAINT GREEN (-5577 2850);
DISPLAY INVISIBLE (-5577 2850);
FORCEADD TAP..6
(-5575 2800);
FORCEPROP 3 LASTPIN (-5525 2800) SIG_NAME M_C_DQ<25>
J 0
(-5515 2810);
DISPLAY 0.659574 (-5515 2810);
PAINT MONO (-5515 2810);
DISPLAY INVISIBLE (-5515 2810);
FORCEPROP 1 LASTPIN (-5525 2800) BN 25
J 0
(-5577 2808);
DISPLAY 0.617021 (-5577 2808);
PAINT PINK (-5577 2808);
FORCEPROP 2 LAST CDS_LIB mstr_standard
J 0
(-5575 2800);
PAINT MONO (-5575 2800);
DISPLAY INVISIBLE (-5575 2800);
FORCEPROP 1 LAST BODY_TYPE PLUMBING
J 0
(-5575 2750);
DISPLAY 1.595745 (-5575 2750);
PAINT GREEN (-5575 2750);
DISPLAY INVISIBLE (-5575 2750);
FORCEPROP 1 LAST HDL_TAP TRUE
J 0
(-5250 2675);
DISPLAY 1.595745 (-5250 2675);
PAINT GREEN (-5250 2675);
DISPLAY INVISIBLE (-5250 2675);
FORCEPROP 1 LAST PATH I48
J 0
(-5577 2800);
DISPLAY 0.872340 (-5577 2800);
PAINT GREEN (-5577 2800);
DISPLAY INVISIBLE (-5577 2800);
FORCEADD TAP..6
(-5575 2900);
FORCEPROP 3 LASTPIN (-5525 2900) SIG_NAME M_C_DQ<27>
J 0
(-5515 2910);
DISPLAY 0.659574 (-5515 2910);
PAINT MONO (-5515 2910);
DISPLAY INVISIBLE (-5515 2910);
FORCEPROP 1 LASTPIN (-5525 2900) BN 27
J 0
(-5577 2908);
DISPLAY 0.617021 (-5577 2908);
PAINT PINK (-5577 2908);
FORCEPROP 2 LAST CDS_LIB mstr_standard
J 0
(-5575 2900);
PAINT MONO (-5575 2900);
DISPLAY INVISIBLE (-5575 2900);
FORCEPROP 1 LAST BODY_TYPE PLUMBING
J 0
(-5575 2850);
DISPLAY 1.595745 (-5575 2850);
PAINT GREEN (-5575 2850);
DISPLAY INVISIBLE (-5575 2850);
FORCEPROP 1 LAST HDL_TAP TRUE
J 0
(-5250 2775);
DISPLAY 1.595745 (-5250 2775);
PAINT GREEN (-5250 2775);
DISPLAY INVISIBLE (-5250 2775);
FORCEPROP 1 LAST PATH I49
J 0
(-5577 2900);
DISPLAY 0.872340 (-5577 2900);
PAINT GREEN (-5577 2900);
DISPLAY INVISIBLE (-5577 2900);
FORCEADD TAP..6
(-5575 650);
FORCEPROP 3 LASTPIN (-5525 650) SIG_NAME M_C_CLK_DN<0>
J 0
(-5515 660);
DISPLAY 0.659574 (-5515 660);
PAINT MONO (-5515 660);
DISPLAY INVISIBLE (-5515 660);
FORCEPROP 1 LASTPIN (-5525 650) BN 0
J 0
(-5577 658);
DISPLAY 0.617021 (-5577 658);
PAINT PINK (-5577 658);
FORCEPROP 2 LAST CDS_LIB mstr_standard
J 0
(-5575 650);
PAINT MONO (-5575 650);
DISPLAY INVISIBLE (-5575 650);
FORCEPROP 1 LAST BODY_TYPE PLUMBING
J 0
(-5575 600);
DISPLAY 1.595745 (-5575 600);
PAINT GREEN (-5575 600);
DISPLAY INVISIBLE (-5575 600);
FORCEPROP 1 LAST HDL_TAP TRUE
J 0
(-5250 525);
DISPLAY 1.595745 (-5250 525);
PAINT GREEN (-5250 525);
DISPLAY INVISIBLE (-5250 525);
FORCEPROP 1 LAST PATH I5
J 0
(-5577 650);
DISPLAY 0.872340 (-5577 650);
PAINT GREEN (-5577 650);
DISPLAY INVISIBLE (-5577 650);
FORCEADD TAP..6
(-5575 2950);
FORCEPROP 3 LASTPIN (-5525 2950) SIG_NAME M_C_DQ<28>
J 0
(-5515 2960);
DISPLAY 0.659574 (-5515 2960);
PAINT MONO (-5515 2960);
DISPLAY INVISIBLE (-5515 2960);
FORCEPROP 1 LASTPIN (-5525 2950) BN 28
J 0
(-5577 2958);
DISPLAY 0.617021 (-5577 2958);
PAINT PINK (-5577 2958);
FORCEPROP 2 LAST CDS_LIB mstr_standard
J 0
(-5575 2950);
PAINT MONO (-5575 2950);
DISPLAY INVISIBLE (-5575 2950);
FORCEPROP 1 LAST BODY_TYPE PLUMBING
J 0
(-5575 2900);
DISPLAY 1.595745 (-5575 2900);
PAINT GREEN (-5575 2900);
DISPLAY INVISIBLE (-5575 2900);
FORCEPROP 1 LAST HDL_TAP TRUE
J 0
(-5250 2825);
DISPLAY 1.595745 (-5250 2825);
PAINT GREEN (-5250 2825);
DISPLAY INVISIBLE (-5250 2825);
FORCEPROP 1 LAST PATH I50
J 0
(-5577 2950);
DISPLAY 0.872340 (-5577 2950);
PAINT GREEN (-5577 2950);
DISPLAY INVISIBLE (-5577 2950);
FORCEADD TAP..6
(-5575 3000);
FORCEPROP 3 LASTPIN (-5525 3000) SIG_NAME M_C_DQ<29>
J 0
(-5515 3010);
DISPLAY 0.659574 (-5515 3010);
PAINT MONO (-5515 3010);
DISPLAY INVISIBLE (-5515 3010);
FORCEPROP 1 LASTPIN (-5525 3000) BN 29
J 0
(-5577 3008);
DISPLAY 0.617021 (-5577 3008);
PAINT PINK (-5577 3008);
FORCEPROP 2 LAST CDS_LIB mstr_standard
J 0
(-5575 3000);
PAINT MONO (-5575 3000);
DISPLAY INVISIBLE (-5575 3000);
FORCEPROP 1 LAST BODY_TYPE PLUMBING
J 0
(-5575 2950);
DISPLAY 1.595745 (-5575 2950);
PAINT GREEN (-5575 2950);
DISPLAY INVISIBLE (-5575 2950);
FORCEPROP 1 LAST HDL_TAP TRUE
J 0
(-5250 2875);
DISPLAY 1.595745 (-5250 2875);
PAINT GREEN (-5250 2875);
DISPLAY INVISIBLE (-5250 2875);
FORCEPROP 1 LAST PATH I51
J 0
(-5577 3000);
DISPLAY 0.872340 (-5577 3000);
PAINT GREEN (-5577 3000);
DISPLAY INVISIBLE (-5577 3000);
FORCEADD TAP..6
(-5575 3050);
FORCEPROP 3 LASTPIN (-5525 3050) SIG_NAME M_C_DQ<30>
J 0
(-5515 3060);
DISPLAY 0.659574 (-5515 3060);
PAINT MONO (-5515 3060);
DISPLAY INVISIBLE (-5515 3060);
FORCEPROP 1 LASTPIN (-5525 3050) BN 30
J 0
(-5577 3058);
DISPLAY 0.617021 (-5577 3058);
PAINT PINK (-5577 3058);
FORCEPROP 2 LAST CDS_LIB mstr_standard
J 0
(-5575 3050);
PAINT MONO (-5575 3050);
DISPLAY INVISIBLE (-5575 3050);
FORCEPROP 1 LAST BODY_TYPE PLUMBING
J 0
(-5575 3000);
DISPLAY 1.595745 (-5575 3000);
PAINT GREEN (-5575 3000);
DISPLAY INVISIBLE (-5575 3000);
FORCEPROP 1 LAST HDL_TAP TRUE
J 0
(-5250 2925);
DISPLAY 1.595745 (-5250 2925);
PAINT GREEN (-5250 2925);
DISPLAY INVISIBLE (-5250 2925);
FORCEPROP 1 LAST PATH I52
J 0
(-5577 3050);
DISPLAY 0.872340 (-5577 3050);
PAINT GREEN (-5577 3050);
DISPLAY INVISIBLE (-5577 3050);
FORCEADD TAP..6
(-5575 3100);
FORCEPROP 3 LASTPIN (-5525 3100) SIG_NAME M_C_DQ<31>
J 0
(-5515 3110);
DISPLAY 0.659574 (-5515 3110);
PAINT MONO (-5515 3110);
DISPLAY INVISIBLE (-5515 3110);
FORCEPROP 1 LASTPIN (-5525 3100) BN 31
J 0
(-5577 3108);
DISPLAY 0.617021 (-5577 3108);
PAINT PINK (-5577 3108);
FORCEPROP 2 LAST CDS_LIB mstr_standard
J 0
(-5575 3100);
PAINT MONO (-5575 3100);
DISPLAY INVISIBLE (-5575 3100);
FORCEPROP 1 LAST BODY_TYPE PLUMBING
J 0
(-5575 3050);
DISPLAY 1.595745 (-5575 3050);
PAINT GREEN (-5575 3050);
DISPLAY INVISIBLE (-5575 3050);
FORCEPROP 1 LAST HDL_TAP TRUE
J 0
(-5250 2975);
DISPLAY 1.595745 (-5250 2975);
PAINT GREEN (-5250 2975);
DISPLAY INVISIBLE (-5250 2975);
FORCEPROP 1 LAST PATH I53
J 0
(-5577 3100);
DISPLAY 0.872340 (-5577 3100);
PAINT GREEN (-5577 3100);
DISPLAY INVISIBLE (-5577 3100);
FORCEADD TAP..6
(-5575 3200);
FORCEPROP 3 LASTPIN (-5525 3200) SIG_NAME M_C_DQ<33>
J 0
(-5515 3210);
DISPLAY 0.659574 (-5515 3210);
PAINT MONO (-5515 3210);
DISPLAY INVISIBLE (-5515 3210);
FORCEPROP 1 LASTPIN (-5525 3200) BN 33
J 0
(-5577 3208);
DISPLAY 0.617021 (-5577 3208);
PAINT PINK (-5577 3208);
FORCEPROP 2 LAST CDS_LIB mstr_standard
J 0
(-5575 3200);
PAINT MONO (-5575 3200);
DISPLAY INVISIBLE (-5575 3200);
FORCEPROP 1 LAST BODY_TYPE PLUMBING
J 0
(-5575 3150);
DISPLAY 1.595745 (-5575 3150);
PAINT GREEN (-5575 3150);
DISPLAY INVISIBLE (-5575 3150);
FORCEPROP 1 LAST HDL_TAP TRUE
J 0
(-5250 3075);
DISPLAY 1.595745 (-5250 3075);
PAINT GREEN (-5250 3075);
DISPLAY INVISIBLE (-5250 3075);
FORCEPROP 1 LAST PATH I54
J 0
(-5577 3200);
DISPLAY 0.872340 (-5577 3200);
PAINT GREEN (-5577 3200);
DISPLAY INVISIBLE (-5577 3200);
FORCEADD TAP..6
(-5575 3250);
FORCEPROP 3 LASTPIN (-5525 3250) SIG_NAME M_C_DQ<34>
J 0
(-5515 3260);
DISPLAY 0.659574 (-5515 3260);
PAINT MONO (-5515 3260);
DISPLAY INVISIBLE (-5515 3260);
FORCEPROP 1 LASTPIN (-5525 3250) BN 34
J 0
(-5577 3258);
DISPLAY 0.617021 (-5577 3258);
PAINT PINK (-5577 3258);
FORCEPROP 2 LAST CDS_LIB mstr_standard
J 0
(-5575 3250);
PAINT MONO (-5575 3250);
DISPLAY INVISIBLE (-5575 3250);
FORCEPROP 1 LAST BODY_TYPE PLUMBING
J 0
(-5575 3200);
DISPLAY 1.595745 (-5575 3200);
PAINT GREEN (-5575 3200);
DISPLAY INVISIBLE (-5575 3200);
FORCEPROP 1 LAST HDL_TAP TRUE
J 0
(-5250 3125);
DISPLAY 1.595745 (-5250 3125);
PAINT GREEN (-5250 3125);
DISPLAY INVISIBLE (-5250 3125);
FORCEPROP 1 LAST PATH I55
J 0
(-5577 3250);
DISPLAY 0.872340 (-5577 3250);
PAINT GREEN (-5577 3250);
DISPLAY INVISIBLE (-5577 3250);
FORCEADD TAP..6
(-5575 3150);
FORCEPROP 3 LASTPIN (-5525 3150) SIG_NAME M_C_DQ<32>
J 0
(-5515 3160);
DISPLAY 0.659574 (-5515 3160);
PAINT MONO (-5515 3160);
DISPLAY INVISIBLE (-5515 3160);
FORCEPROP 1 LASTPIN (-5525 3150) BN 32
J 0
(-5577 3158);
DISPLAY 0.617021 (-5577 3158);
PAINT PINK (-5577 3158);
FORCEPROP 2 LAST CDS_LIB mstr_standard
J 0
(-5575 3150);
PAINT MONO (-5575 3150);
DISPLAY INVISIBLE (-5575 3150);
FORCEPROP 1 LAST BODY_TYPE PLUMBING
J 0
(-5575 3100);
DISPLAY 1.595745 (-5575 3100);
PAINT GREEN (-5575 3100);
DISPLAY INVISIBLE (-5575 3100);
FORCEPROP 1 LAST HDL_TAP TRUE
J 0
(-5250 3025);
DISPLAY 1.595745 (-5250 3025);
PAINT GREEN (-5250 3025);
DISPLAY INVISIBLE (-5250 3025);
FORCEPROP 1 LAST PATH I56
J 0
(-5577 3150);
DISPLAY 0.872340 (-5577 3150);
PAINT GREEN (-5577 3150);
DISPLAY INVISIBLE (-5577 3150);
FORCEADD TAP..6
(-5575 3350);
FORCEPROP 3 LASTPIN (-5525 3350) SIG_NAME M_C_DQ<36>
J 0
(-5515 3360);
DISPLAY 0.659574 (-5515 3360);
PAINT MONO (-5515 3360);
DISPLAY INVISIBLE (-5515 3360);
FORCEPROP 1 LASTPIN (-5525 3350) BN 36
J 0
(-5577 3358);
DISPLAY 0.617021 (-5577 3358);
PAINT PINK (-5577 3358);
FORCEPROP 2 LAST CDS_LIB mstr_standard
J 0
(-5575 3350);
PAINT MONO (-5575 3350);
DISPLAY INVISIBLE (-5575 3350);
FORCEPROP 1 LAST BODY_TYPE PLUMBING
J 0
(-5575 3300);
DISPLAY 1.595745 (-5575 3300);
PAINT GREEN (-5575 3300);
DISPLAY INVISIBLE (-5575 3300);
FORCEPROP 1 LAST HDL_TAP TRUE
J 0
(-5250 3225);
DISPLAY 1.595745 (-5250 3225);
PAINT GREEN (-5250 3225);
DISPLAY INVISIBLE (-5250 3225);
FORCEPROP 1 LAST PATH I57
J 0
(-5577 3350);
DISPLAY 0.872340 (-5577 3350);
PAINT GREEN (-5577 3350);
DISPLAY INVISIBLE (-5577 3350);
FORCEADD TAP..6
(-5575 3300);
FORCEPROP 3 LASTPIN (-5525 3300) SIG_NAME M_C_DQ<35>
J 0
(-5515 3310);
DISPLAY 0.659574 (-5515 3310);
PAINT MONO (-5515 3310);
DISPLAY INVISIBLE (-5515 3310);
FORCEPROP 1 LASTPIN (-5525 3300) BN 35
J 0
(-5577 3308);
DISPLAY 0.617021 (-5577 3308);
PAINT PINK (-5577 3308);
FORCEPROP 2 LAST CDS_LIB mstr_standard
J 0
(-5575 3300);
PAINT MONO (-5575 3300);
DISPLAY INVISIBLE (-5575 3300);
FORCEPROP 1 LAST BODY_TYPE PLUMBING
J 0
(-5575 3250);
DISPLAY 1.595745 (-5575 3250);
PAINT GREEN (-5575 3250);
DISPLAY INVISIBLE (-5575 3250);
FORCEPROP 1 LAST HDL_TAP TRUE
J 0
(-5250 3175);
DISPLAY 1.595745 (-5250 3175);
PAINT GREEN (-5250 3175);
DISPLAY INVISIBLE (-5250 3175);
FORCEPROP 1 LAST PATH I58
J 0
(-5577 3300);
DISPLAY 0.872340 (-5577 3300);
PAINT GREEN (-5577 3300);
DISPLAY INVISIBLE (-5577 3300);
FORCEADD TAP..6
(-5575 3400);
FORCEPROP 3 LASTPIN (-5525 3400) SIG_NAME M_C_DQ<37>
J 0
(-5515 3410);
DISPLAY 0.659574 (-5515 3410);
PAINT MONO (-5515 3410);
DISPLAY INVISIBLE (-5515 3410);
FORCEPROP 1 LASTPIN (-5525 3400) BN 37
J 0
(-5577 3408);
DISPLAY 0.617021 (-5577 3408);
PAINT PINK (-5577 3408);
FORCEPROP 2 LAST CDS_LIB mstr_standard
J 0
(-5575 3400);
PAINT MONO (-5575 3400);
DISPLAY INVISIBLE (-5575 3400);
FORCEPROP 1 LAST BODY_TYPE PLUMBING
J 0
(-5575 3350);
DISPLAY 1.595745 (-5575 3350);
PAINT GREEN (-5575 3350);
DISPLAY INVISIBLE (-5575 3350);
FORCEPROP 1 LAST HDL_TAP TRUE
J 0
(-5250 3275);
DISPLAY 1.595745 (-5250 3275);
PAINT GREEN (-5250 3275);
DISPLAY INVISIBLE (-5250 3275);
FORCEPROP 1 LAST PATH I59
J 0
(-5577 3400);
DISPLAY 0.872340 (-5577 3400);
PAINT GREEN (-5577 3400);
DISPLAY INVISIBLE (-5577 3400);
FORCEADD TAP..6
(-5575 700);
FORCEPROP 3 LASTPIN (-5525 700) SIG_NAME M_C_CLK_DN<1>
J 0
(-5515 710);
DISPLAY 0.659574 (-5515 710);
PAINT MONO (-5515 710);
DISPLAY INVISIBLE (-5515 710);
FORCEPROP 1 LASTPIN (-5525 700) BN 1
J 0
(-5577 708);
DISPLAY 0.617021 (-5577 708);
PAINT PINK (-5577 708);
FORCEPROP 2 LAST CDS_LIB mstr_standard
J 0
(-5575 700);
PAINT MONO (-5575 700);
DISPLAY INVISIBLE (-5575 700);
FORCEPROP 1 LAST BODY_TYPE PLUMBING
J 0
(-5575 650);
DISPLAY 1.595745 (-5575 650);
PAINT GREEN (-5575 650);
DISPLAY INVISIBLE (-5575 650);
FORCEPROP 1 LAST HDL_TAP TRUE
J 0
(-5250 575);
DISPLAY 1.595745 (-5250 575);
PAINT GREEN (-5250 575);
DISPLAY INVISIBLE (-5250 575);
FORCEPROP 1 LAST PATH I6
J 0
(-5577 700);
DISPLAY 0.872340 (-5577 700);
PAINT GREEN (-5577 700);
DISPLAY INVISIBLE (-5577 700);
FORCEADD TAP..6
(-5575 3450);
FORCEPROP 3 LASTPIN (-5525 3450) SIG_NAME M_C_DQ<38>
J 0
(-5515 3460);
DISPLAY 0.659574 (-5515 3460);
PAINT MONO (-5515 3460);
DISPLAY INVISIBLE (-5515 3460);
FORCEPROP 1 LASTPIN (-5525 3450) BN 38
J 0
(-5577 3458);
DISPLAY 0.617021 (-5577 3458);
PAINT PINK (-5577 3458);
FORCEPROP 2 LAST CDS_LIB mstr_standard
J 0
(-5575 3450);
PAINT MONO (-5575 3450);
DISPLAY INVISIBLE (-5575 3450);
FORCEPROP 1 LAST BODY_TYPE PLUMBING
J 0
(-5575 3400);
DISPLAY 1.595745 (-5575 3400);
PAINT GREEN (-5575 3400);
DISPLAY INVISIBLE (-5575 3400);
FORCEPROP 1 LAST HDL_TAP TRUE
J 0
(-5250 3325);
DISPLAY 1.595745 (-5250 3325);
PAINT GREEN (-5250 3325);
DISPLAY INVISIBLE (-5250 3325);
FORCEPROP 1 LAST PATH I60
J 0
(-5577 3450);
DISPLAY 0.872340 (-5577 3450);
PAINT GREEN (-5577 3450);
DISPLAY INVISIBLE (-5577 3450);
FORCEADD TAP..6
(-5575 3500);
FORCEPROP 3 LASTPIN (-5525 3500) SIG_NAME M_C_DQ<39>
J 0
(-5515 3510);
DISPLAY 0.659574 (-5515 3510);
PAINT MONO (-5515 3510);
DISPLAY INVISIBLE (-5515 3510);
FORCEPROP 1 LASTPIN (-5525 3500) BN 39
J 0
(-5577 3508);
DISPLAY 0.617021 (-5577 3508);
PAINT PINK (-5577 3508);
FORCEPROP 2 LAST CDS_LIB mstr_standard
J 0
(-5575 3500);
PAINT MONO (-5575 3500);
DISPLAY INVISIBLE (-5575 3500);
FORCEPROP 1 LAST BODY_TYPE PLUMBING
J 0
(-5575 3450);
DISPLAY 1.595745 (-5575 3450);
PAINT GREEN (-5575 3450);
DISPLAY INVISIBLE (-5575 3450);
FORCEPROP 1 LAST HDL_TAP TRUE
J 0
(-5250 3375);
DISPLAY 1.595745 (-5250 3375);
PAINT GREEN (-5250 3375);
DISPLAY INVISIBLE (-5250 3375);
FORCEPROP 1 LAST PATH I61
J 0
(-5577 3500);
DISPLAY 0.872340 (-5577 3500);
PAINT GREEN (-5577 3500);
DISPLAY INVISIBLE (-5577 3500);
FORCEADD TAP..6
(-5575 3600);
FORCEPROP 3 LASTPIN (-5525 3600) SIG_NAME M_C_DQ<41>
J 0
(-5515 3610);
DISPLAY 0.659574 (-5515 3610);
PAINT MONO (-5515 3610);
DISPLAY INVISIBLE (-5515 3610);
FORCEPROP 1 LASTPIN (-5525 3600) BN 41
J 0
(-5577 3608);
DISPLAY 0.617021 (-5577 3608);
PAINT PINK (-5577 3608);
FORCEPROP 2 LAST CDS_LIB mstr_standard
J 0
(-5575 3600);
PAINT MONO (-5575 3600);
DISPLAY INVISIBLE (-5575 3600);
FORCEPROP 1 LAST BODY_TYPE PLUMBING
J 0
(-5575 3550);
DISPLAY 1.595745 (-5575 3550);
PAINT GREEN (-5575 3550);
DISPLAY INVISIBLE (-5575 3550);
FORCEPROP 1 LAST HDL_TAP TRUE
J 0
(-5250 3475);
DISPLAY 1.595745 (-5250 3475);
PAINT GREEN (-5250 3475);
DISPLAY INVISIBLE (-5250 3475);
FORCEPROP 1 LAST PATH I62
J 0
(-5577 3600);
DISPLAY 0.872340 (-5577 3600);
PAINT GREEN (-5577 3600);
DISPLAY INVISIBLE (-5577 3600);
FORCEADD TAP..6
(-5575 3550);
FORCEPROP 3 LASTPIN (-5525 3550) SIG_NAME M_C_DQ<40>
J 0
(-5515 3560);
DISPLAY 0.659574 (-5515 3560);
PAINT MONO (-5515 3560);
DISPLAY INVISIBLE (-5515 3560);
FORCEPROP 1 LASTPIN (-5525 3550) BN 40
J 0
(-5577 3558);
DISPLAY 0.617021 (-5577 3558);
PAINT PINK (-5577 3558);
FORCEPROP 2 LAST CDS_LIB mstr_standard
J 0
(-5575 3550);
PAINT MONO (-5575 3550);
DISPLAY INVISIBLE (-5575 3550);
FORCEPROP 1 LAST BODY_TYPE PLUMBING
J 0
(-5575 3500);
DISPLAY 1.595745 (-5575 3500);
PAINT GREEN (-5575 3500);
DISPLAY INVISIBLE (-5575 3500);
FORCEPROP 1 LAST HDL_TAP TRUE
J 0
(-5250 3425);
DISPLAY 1.595745 (-5250 3425);
PAINT GREEN (-5250 3425);
DISPLAY INVISIBLE (-5250 3425);
FORCEPROP 1 LAST PATH I63
J 0
(-5577 3550);
DISPLAY 0.872340 (-5577 3550);
PAINT GREEN (-5577 3550);
DISPLAY INVISIBLE (-5577 3550);
FORCEADD TAP..6
(-5575 3650);
FORCEPROP 3 LASTPIN (-5525 3650) SIG_NAME M_C_DQ<42>
J 0
(-5515 3660);
DISPLAY 0.659574 (-5515 3660);
PAINT MONO (-5515 3660);
DISPLAY INVISIBLE (-5515 3660);
FORCEPROP 1 LASTPIN (-5525 3650) BN 42
J 0
(-5577 3658);
DISPLAY 0.617021 (-5577 3658);
PAINT PINK (-5577 3658);
FORCEPROP 2 LAST CDS_LIB mstr_standard
J 0
(-5575 3650);
PAINT MONO (-5575 3650);
DISPLAY INVISIBLE (-5575 3650);
FORCEPROP 1 LAST BODY_TYPE PLUMBING
J 0
(-5575 3600);
DISPLAY 1.595745 (-5575 3600);
PAINT GREEN (-5575 3600);
DISPLAY INVISIBLE (-5575 3600);
FORCEPROP 1 LAST HDL_TAP TRUE
J 0
(-5250 3525);
DISPLAY 1.595745 (-5250 3525);
PAINT GREEN (-5250 3525);
DISPLAY INVISIBLE (-5250 3525);
FORCEPROP 1 LAST PATH I64
J 0
(-5577 3650);
DISPLAY 0.872340 (-5577 3650);
PAINT GREEN (-5577 3650);
DISPLAY INVISIBLE (-5577 3650);
FORCEADD TAP..6
(-5575 3700);
FORCEPROP 3 LASTPIN (-5525 3700) SIG_NAME M_C_DQ<43>
J 0
(-5515 3710);
DISPLAY 0.659574 (-5515 3710);
PAINT MONO (-5515 3710);
DISPLAY INVISIBLE (-5515 3710);
FORCEPROP 1 LASTPIN (-5525 3700) BN 43
J 0
(-5577 3708);
DISPLAY 0.617021 (-5577 3708);
PAINT PINK (-5577 3708);
FORCEPROP 2 LAST CDS_LIB mstr_standard
J 0
(-5575 3700);
PAINT MONO (-5575 3700);
DISPLAY INVISIBLE (-5575 3700);
FORCEPROP 1 LAST BODY_TYPE PLUMBING
J 0
(-5575 3650);
DISPLAY 1.595745 (-5575 3650);
PAINT GREEN (-5575 3650);
DISPLAY INVISIBLE (-5575 3650);
FORCEPROP 1 LAST HDL_TAP TRUE
J 0
(-5250 3575);
DISPLAY 1.595745 (-5250 3575);
PAINT GREEN (-5250 3575);
DISPLAY INVISIBLE (-5250 3575);
FORCEPROP 1 LAST PATH I65
J 0
(-5577 3700);
DISPLAY 0.872340 (-5577 3700);
PAINT GREEN (-5577 3700);
DISPLAY INVISIBLE (-5577 3700);
FORCEADD TAP..6
(-5575 3750);
FORCEPROP 3 LASTPIN (-5525 3750) SIG_NAME M_C_DQ<44>
J 0
(-5515 3760);
DISPLAY 0.659574 (-5515 3760);
PAINT MONO (-5515 3760);
DISPLAY INVISIBLE (-5515 3760);
FORCEPROP 1 LASTPIN (-5525 3750) BN 44
J 0
(-5577 3758);
DISPLAY 0.617021 (-5577 3758);
PAINT PINK (-5577 3758);
FORCEPROP 2 LAST CDS_LIB mstr_standard
J 0
(-5575 3750);
PAINT MONO (-5575 3750);
DISPLAY INVISIBLE (-5575 3750);
FORCEPROP 1 LAST BODY_TYPE PLUMBING
J 0
(-5575 3700);
DISPLAY 1.595745 (-5575 3700);
PAINT GREEN (-5575 3700);
DISPLAY INVISIBLE (-5575 3700);
FORCEPROP 1 LAST HDL_TAP TRUE
J 0
(-5250 3625);
DISPLAY 1.595745 (-5250 3625);
PAINT GREEN (-5250 3625);
DISPLAY INVISIBLE (-5250 3625);
FORCEPROP 1 LAST PATH I66
J 0
(-5577 3750);
DISPLAY 0.872340 (-5577 3750);
PAINT GREEN (-5577 3750);
DISPLAY INVISIBLE (-5577 3750);
FORCEADD TAP..6
(-5575 3800);
FORCEPROP 3 LASTPIN (-5525 3800) SIG_NAME M_C_DQ<45>
J 0
(-5515 3810);
DISPLAY 0.659574 (-5515 3810);
PAINT MONO (-5515 3810);
DISPLAY INVISIBLE (-5515 3810);
FORCEPROP 1 LASTPIN (-5525 3800) BN 45
J 0
(-5577 3808);
DISPLAY 0.617021 (-5577 3808);
PAINT PINK (-5577 3808);
FORCEPROP 2 LAST CDS_LIB mstr_standard
J 0
(-5575 3800);
PAINT MONO (-5575 3800);
DISPLAY INVISIBLE (-5575 3800);
FORCEPROP 1 LAST BODY_TYPE PLUMBING
J 0
(-5575 3750);
DISPLAY 1.595745 (-5575 3750);
PAINT GREEN (-5575 3750);
DISPLAY INVISIBLE (-5575 3750);
FORCEPROP 1 LAST HDL_TAP TRUE
J 0
(-5250 3675);
DISPLAY 1.595745 (-5250 3675);
PAINT GREEN (-5250 3675);
DISPLAY INVISIBLE (-5250 3675);
FORCEPROP 1 LAST PATH I67
J 0
(-5577 3800);
DISPLAY 0.872340 (-5577 3800);
PAINT GREEN (-5577 3800);
DISPLAY INVISIBLE (-5577 3800);
FORCEADD TAP..6
(-5575 3850);
FORCEPROP 3 LASTPIN (-5525 3850) SIG_NAME M_C_DQ<46>
J 0
(-5515 3860);
DISPLAY 0.659574 (-5515 3860);
PAINT MONO (-5515 3860);
DISPLAY INVISIBLE (-5515 3860);
FORCEPROP 1 LASTPIN (-5525 3850) BN 46
J 0
(-5577 3858);
DISPLAY 0.617021 (-5577 3858);
PAINT PINK (-5577 3858);
FORCEPROP 2 LAST CDS_LIB mstr_standard
J 0
(-5575 3850);
PAINT MONO (-5575 3850);
DISPLAY INVISIBLE (-5575 3850);
FORCEPROP 1 LAST BODY_TYPE PLUMBING
J 0
(-5575 3800);
DISPLAY 1.595745 (-5575 3800);
PAINT GREEN (-5575 3800);
DISPLAY INVISIBLE (-5575 3800);
FORCEPROP 1 LAST HDL_TAP TRUE
J 0
(-5250 3725);
DISPLAY 1.595745 (-5250 3725);
PAINT GREEN (-5250 3725);
DISPLAY INVISIBLE (-5250 3725);
FORCEPROP 1 LAST PATH I68
J 0
(-5577 3850);
DISPLAY 0.872340 (-5577 3850);
PAINT GREEN (-5577 3850);
DISPLAY INVISIBLE (-5577 3850);
FORCEADD TAP..6
(-5575 3900);
FORCEPROP 3 LASTPIN (-5525 3900) SIG_NAME M_C_DQ<47>
J 0
(-5515 3910);
DISPLAY 0.659574 (-5515 3910);
PAINT MONO (-5515 3910);
DISPLAY INVISIBLE (-5515 3910);
FORCEPROP 1 LASTPIN (-5525 3900) BN 47
J 0
(-5577 3908);
DISPLAY 0.617021 (-5577 3908);
PAINT PINK (-5577 3908);
FORCEPROP 2 LAST CDS_LIB mstr_standard
J 0
(-5575 3900);
PAINT MONO (-5575 3900);
DISPLAY INVISIBLE (-5575 3900);
FORCEPROP 1 LAST BODY_TYPE PLUMBING
J 0
(-5575 3850);
DISPLAY 1.595745 (-5575 3850);
PAINT GREEN (-5575 3850);
DISPLAY INVISIBLE (-5575 3850);
FORCEPROP 1 LAST HDL_TAP TRUE
J 0
(-5250 3775);
DISPLAY 1.595745 (-5250 3775);
PAINT GREEN (-5250 3775);
DISPLAY INVISIBLE (-5250 3775);
FORCEPROP 1 LAST PATH I69
J 0
(-5577 3900);
DISPLAY 0.872340 (-5577 3900);
PAINT GREEN (-5577 3900);
DISPLAY INVISIBLE (-5577 3900);
FORCEADD TAP..6
(-5575 750);
FORCEPROP 3 LASTPIN (-5525 750) SIG_NAME M_C_CLK_DN<2>
J 0
(-5515 760);
DISPLAY 0.659574 (-5515 760);
PAINT MONO (-5515 760);
DISPLAY INVISIBLE (-5515 760);
FORCEPROP 1 LASTPIN (-5525 750) BN 2
J 0
(-5577 758);
DISPLAY 0.617021 (-5577 758);
PAINT PINK (-5577 758);
FORCEPROP 2 LAST CDS_LIB mstr_standard
J 0
(-5575 750);
PAINT MONO (-5575 750);
DISPLAY INVISIBLE (-5575 750);
FORCEPROP 1 LAST BODY_TYPE PLUMBING
J 0
(-5575 700);
DISPLAY 1.595745 (-5575 700);
PAINT GREEN (-5575 700);
DISPLAY INVISIBLE (-5575 700);
FORCEPROP 1 LAST HDL_TAP TRUE
J 0
(-5250 625);
DISPLAY 1.595745 (-5250 625);
PAINT GREEN (-5250 625);
DISPLAY INVISIBLE (-5250 625);
FORCEPROP 1 LAST PATH I7
J 0
(-5577 750);
DISPLAY 0.872340 (-5577 750);
PAINT GREEN (-5577 750);
DISPLAY INVISIBLE (-5577 750);
FORCEADD TAP..6
(-5575 3950);
FORCEPROP 3 LASTPIN (-5525 3950) SIG_NAME M_C_DQ<48>
J 0
(-5515 3960);
DISPLAY 0.659574 (-5515 3960);
PAINT MONO (-5515 3960);
DISPLAY INVISIBLE (-5515 3960);
FORCEPROP 1 LASTPIN (-5525 3950) BN 48
J 0
(-5577 3958);
DISPLAY 0.617021 (-5577 3958);
PAINT PINK (-5577 3958);
FORCEPROP 2 LAST CDS_LIB mstr_standard
J 0
(-5575 3950);
PAINT MONO (-5575 3950);
DISPLAY INVISIBLE (-5575 3950);
FORCEPROP 1 LAST BODY_TYPE PLUMBING
J 0
(-5575 3900);
DISPLAY 1.595745 (-5575 3900);
PAINT GREEN (-5575 3900);
DISPLAY INVISIBLE (-5575 3900);
FORCEPROP 1 LAST HDL_TAP TRUE
J 0
(-5250 3825);
DISPLAY 1.595745 (-5250 3825);
PAINT GREEN (-5250 3825);
DISPLAY INVISIBLE (-5250 3825);
FORCEPROP 1 LAST PATH I70
J 0
(-5577 3950);
DISPLAY 0.872340 (-5577 3950);
PAINT GREEN (-5577 3950);
DISPLAY INVISIBLE (-5577 3950);
FORCEADD TAP..6
(-5575 4000);
FORCEPROP 3 LASTPIN (-5525 4000) SIG_NAME M_C_DQ<49>
J 0
(-5515 4010);
DISPLAY 0.659574 (-5515 4010);
PAINT MONO (-5515 4010);
DISPLAY INVISIBLE (-5515 4010);
FORCEPROP 1 LASTPIN (-5525 4000) BN 49
J 0
(-5577 4008);
DISPLAY 0.617021 (-5577 4008);
PAINT PINK (-5577 4008);
FORCEPROP 2 LAST CDS_LIB mstr_standard
J 0
(-5575 4000);
PAINT MONO (-5575 4000);
DISPLAY INVISIBLE (-5575 4000);
FORCEPROP 1 LAST BODY_TYPE PLUMBING
J 0
(-5575 3950);
DISPLAY 1.595745 (-5575 3950);
PAINT GREEN (-5575 3950);
DISPLAY INVISIBLE (-5575 3950);
FORCEPROP 1 LAST HDL_TAP TRUE
J 0
(-5250 3875);
DISPLAY 1.595745 (-5250 3875);
PAINT GREEN (-5250 3875);
DISPLAY INVISIBLE (-5250 3875);
FORCEPROP 1 LAST PATH I71
J 0
(-5577 4000);
DISPLAY 0.872340 (-5577 4000);
PAINT GREEN (-5577 4000);
DISPLAY INVISIBLE (-5577 4000);
FORCEADD OFFPAGE..6
(-6425 4825);
FORCEPROP 2 LAST $XR0 47 
J 0
(-6674 4825);
DISPLAY 0.638298 (-6674 4825);
PAINT MONO (-6674 4825);
FORCEPROP 2 LAST $XR1 48 
J 0
(-6764 4825);
DISPLAY 0.638298 (-6764 4825);
PAINT MONO (-6764 4825);
FORCEPROP 2 LAST CDS_LIB mstr_standard
J 0
(-6425 4825);
PAINT MONO (-6425 4825);
DISPLAY INVISIBLE (-6425 4825);
FORCEPROP 1 LAST OFFPAGE TRUE
J 0
(-6100 4700);
DISPLAY 1.170213 (-6100 4700);
PAINT GREEN (-6100 4700);
DISPLAY INVISIBLE (-6100 4700);
FORCEPROP 1 LAST COMMENT_BODY TRUE
J 0
(-6325 4750);
DISPLAY 1.170213 (-6325 4750);
PAINT GREEN (-6325 4750);
DISPLAY INVISIBLE (-6325 4750);
FORCEPROP 2 LAST PATH I72
J 0
(-6375 4900);
DISPLAY 1.021277 (-6375 4900);
PAINT ORANGE (-6375 4900);
DISPLAY INVISIBLE (-6375 4900);
FORCEADD TAP..6
(-5575 4100);
FORCEPROP 3 LASTPIN (-5525 4100) SIG_NAME M_C_DQ<51>
J 0
(-5515 4110);
DISPLAY 0.659574 (-5515 4110);
PAINT MONO (-5515 4110);
DISPLAY INVISIBLE (-5515 4110);
FORCEPROP 1 LASTPIN (-5525 4100) BN 51
J 0
(-5577 4108);
DISPLAY 0.617021 (-5577 4108);
PAINT PINK (-5577 4108);
FORCEPROP 2 LAST CDS_LIB mstr_standard
J 0
(-5575 4100);
PAINT MONO (-5575 4100);
DISPLAY INVISIBLE (-5575 4100);
FORCEPROP 1 LAST BODY_TYPE PLUMBING
J 0
(-5575 4050);
DISPLAY 1.595745 (-5575 4050);
PAINT GREEN (-5575 4050);
DISPLAY INVISIBLE (-5575 4050);
FORCEPROP 1 LAST HDL_TAP TRUE
J 0
(-5250 3975);
DISPLAY 1.595745 (-5250 3975);
PAINT GREEN (-5250 3975);
DISPLAY INVISIBLE (-5250 3975);
FORCEPROP 1 LAST PATH I73
J 0
(-5577 4100);
DISPLAY 0.872340 (-5577 4100);
PAINT GREEN (-5577 4100);
DISPLAY INVISIBLE (-5577 4100);
FORCEADD TAP..6
(-5575 4050);
FORCEPROP 3 LASTPIN (-5525 4050) SIG_NAME M_C_DQ<50>
J 0
(-5515 4060);
DISPLAY 0.659574 (-5515 4060);
PAINT MONO (-5515 4060);
DISPLAY INVISIBLE (-5515 4060);
FORCEPROP 1 LASTPIN (-5525 4050) BN 50
J 0
(-5577 4058);
DISPLAY 0.617021 (-5577 4058);
PAINT PINK (-5577 4058);
FORCEPROP 2 LAST CDS_LIB mstr_standard
J 0
(-5575 4050);
PAINT MONO (-5575 4050);
DISPLAY INVISIBLE (-5575 4050);
FORCEPROP 1 LAST BODY_TYPE PLUMBING
J 0
(-5575 4000);
DISPLAY 1.595745 (-5575 4000);
PAINT GREEN (-5575 4000);
DISPLAY INVISIBLE (-5575 4000);
FORCEPROP 1 LAST HDL_TAP TRUE
J 0
(-5250 3925);
DISPLAY 1.595745 (-5250 3925);
PAINT GREEN (-5250 3925);
DISPLAY INVISIBLE (-5250 3925);
FORCEPROP 1 LAST PATH I74
J 0
(-5577 4050);
DISPLAY 0.872340 (-5577 4050);
PAINT GREEN (-5577 4050);
DISPLAY INVISIBLE (-5577 4050);
FORCEADD TAP..6
(-5575 4150);
FORCEPROP 3 LASTPIN (-5525 4150) SIG_NAME M_C_DQ<52>
J 0
(-5515 4160);
DISPLAY 0.659574 (-5515 4160);
PAINT MONO (-5515 4160);
DISPLAY INVISIBLE (-5515 4160);
FORCEPROP 1 LASTPIN (-5525 4150) BN 52
J 0
(-5577 4158);
DISPLAY 0.617021 (-5577 4158);
PAINT PINK (-5577 4158);
FORCEPROP 2 LAST CDS_LIB mstr_standard
J 0
(-5575 4150);
PAINT MONO (-5575 4150);
DISPLAY INVISIBLE (-5575 4150);
FORCEPROP 1 LAST BODY_TYPE PLUMBING
J 0
(-5575 4100);
DISPLAY 1.595745 (-5575 4100);
PAINT GREEN (-5575 4100);
DISPLAY INVISIBLE (-5575 4100);
FORCEPROP 1 LAST HDL_TAP TRUE
J 0
(-5250 4025);
DISPLAY 1.595745 (-5250 4025);
PAINT GREEN (-5250 4025);
DISPLAY INVISIBLE (-5250 4025);
FORCEPROP 1 LAST PATH I75
J 0
(-5577 4150);
DISPLAY 0.872340 (-5577 4150);
PAINT GREEN (-5577 4150);
DISPLAY INVISIBLE (-5577 4150);
FORCEADD TAP..6
(-5575 4200);
FORCEPROP 3 LASTPIN (-5525 4200) SIG_NAME M_C_DQ<53>
J 0
(-5515 4210);
DISPLAY 0.659574 (-5515 4210);
PAINT MONO (-5515 4210);
DISPLAY INVISIBLE (-5515 4210);
FORCEPROP 1 LASTPIN (-5525 4200) BN 53
J 0
(-5577 4208);
DISPLAY 0.617021 (-5577 4208);
PAINT PINK (-5577 4208);
FORCEPROP 2 LAST CDS_LIB mstr_standard
J 0
(-5575 4200);
PAINT MONO (-5575 4200);
DISPLAY INVISIBLE (-5575 4200);
FORCEPROP 1 LAST BODY_TYPE PLUMBING
J 0
(-5575 4150);
DISPLAY 1.595745 (-5575 4150);
PAINT GREEN (-5575 4150);
DISPLAY INVISIBLE (-5575 4150);
FORCEPROP 1 LAST HDL_TAP TRUE
J 0
(-5250 4075);
DISPLAY 1.595745 (-5250 4075);
PAINT GREEN (-5250 4075);
DISPLAY INVISIBLE (-5250 4075);
FORCEPROP 1 LAST PATH I76
J 0
(-5577 4200);
DISPLAY 0.872340 (-5577 4200);
PAINT GREEN (-5577 4200);
DISPLAY INVISIBLE (-5577 4200);
FORCEADD TAP..6
(-5575 4250);
FORCEPROP 3 LASTPIN (-5525 4250) SIG_NAME M_C_DQ<54>
J 0
(-5515 4260);
DISPLAY 0.659574 (-5515 4260);
PAINT MONO (-5515 4260);
DISPLAY INVISIBLE (-5515 4260);
FORCEPROP 1 LASTPIN (-5525 4250) BN 54
J 0
(-5577 4258);
DISPLAY 0.617021 (-5577 4258);
PAINT PINK (-5577 4258);
FORCEPROP 2 LAST CDS_LIB mstr_standard
J 0
(-5575 4250);
PAINT MONO (-5575 4250);
DISPLAY INVISIBLE (-5575 4250);
FORCEPROP 1 LAST BODY_TYPE PLUMBING
J 0
(-5575 4200);
DISPLAY 1.595745 (-5575 4200);
PAINT GREEN (-5575 4200);
DISPLAY INVISIBLE (-5575 4200);
FORCEPROP 1 LAST HDL_TAP TRUE
J 0
(-5250 4125);
DISPLAY 1.595745 (-5250 4125);
PAINT GREEN (-5250 4125);
DISPLAY INVISIBLE (-5250 4125);
FORCEPROP 1 LAST PATH I77
J 0
(-5577 4250);
DISPLAY 0.872340 (-5577 4250);
PAINT GREEN (-5577 4250);
DISPLAY INVISIBLE (-5577 4250);
FORCEADD TAP..6
(-5575 4300);
FORCEPROP 3 LASTPIN (-5525 4300) SIG_NAME M_C_DQ<55>
J 0
(-5515 4310);
DISPLAY 0.659574 (-5515 4310);
PAINT MONO (-5515 4310);
DISPLAY INVISIBLE (-5515 4310);
FORCEPROP 1 LASTPIN (-5525 4300) BN 55
J 0
(-5577 4308);
DISPLAY 0.617021 (-5577 4308);
PAINT PINK (-5577 4308);
FORCEPROP 2 LAST CDS_LIB mstr_standard
J 0
(-5575 4300);
PAINT MONO (-5575 4300);
DISPLAY INVISIBLE (-5575 4300);
FORCEPROP 1 LAST BODY_TYPE PLUMBING
J 0
(-5575 4250);
DISPLAY 1.595745 (-5575 4250);
PAINT GREEN (-5575 4250);
DISPLAY INVISIBLE (-5575 4250);
FORCEPROP 1 LAST HDL_TAP TRUE
J 0
(-5250 4175);
DISPLAY 1.595745 (-5250 4175);
PAINT GREEN (-5250 4175);
DISPLAY INVISIBLE (-5250 4175);
FORCEPROP 1 LAST PATH I78
J 0
(-5577 4300);
DISPLAY 0.872340 (-5577 4300);
PAINT GREEN (-5577 4300);
DISPLAY INVISIBLE (-5577 4300);
FORCEADD TAP..6
(-5575 4350);
FORCEPROP 3 LASTPIN (-5525 4350) SIG_NAME M_C_DQ<56>
J 0
(-5515 4360);
DISPLAY 0.659574 (-5515 4360);
PAINT MONO (-5515 4360);
DISPLAY INVISIBLE (-5515 4360);
FORCEPROP 1 LASTPIN (-5525 4350) BN 56
J 0
(-5577 4358);
DISPLAY 0.617021 (-5577 4358);
PAINT PINK (-5577 4358);
FORCEPROP 2 LAST CDS_LIB mstr_standard
J 0
(-5575 4350);
PAINT MONO (-5575 4350);
DISPLAY INVISIBLE (-5575 4350);
FORCEPROP 1 LAST BODY_TYPE PLUMBING
J 0
(-5575 4300);
DISPLAY 1.595745 (-5575 4300);
PAINT GREEN (-5575 4300);
DISPLAY INVISIBLE (-5575 4300);
FORCEPROP 1 LAST HDL_TAP TRUE
J 0
(-5250 4225);
DISPLAY 1.595745 (-5250 4225);
PAINT GREEN (-5250 4225);
DISPLAY INVISIBLE (-5250 4225);
FORCEPROP 1 LAST PATH I79
J 0
(-5577 4350);
DISPLAY 0.872340 (-5577 4350);
PAINT GREEN (-5577 4350);
DISPLAY INVISIBLE (-5577 4350);
FORCEADD TAP..6
(-5575 800);
FORCEPROP 3 LASTPIN (-5525 800) SIG_NAME M_C_CLK_DN<3>
J 0
(-5515 810);
DISPLAY 0.659574 (-5515 810);
PAINT MONO (-5515 810);
DISPLAY INVISIBLE (-5515 810);
FORCEPROP 1 LASTPIN (-5525 800) BN 3
J 0
(-5577 808);
DISPLAY 0.617021 (-5577 808);
PAINT PINK (-5577 808);
FORCEPROP 2 LAST CDS_LIB mstr_standard
J 0
(-5575 800);
PAINT MONO (-5575 800);
DISPLAY INVISIBLE (-5575 800);
FORCEPROP 1 LAST BODY_TYPE PLUMBING
J 0
(-5575 750);
DISPLAY 1.595745 (-5575 750);
PAINT GREEN (-5575 750);
DISPLAY INVISIBLE (-5575 750);
FORCEPROP 1 LAST HDL_TAP TRUE
J 0
(-5250 675);
DISPLAY 1.595745 (-5250 675);
PAINT GREEN (-5250 675);
DISPLAY INVISIBLE (-5250 675);
FORCEPROP 1 LAST PATH I8
J 0
(-5577 800);
DISPLAY 0.872340 (-5577 800);
PAINT GREEN (-5577 800);
DISPLAY INVISIBLE (-5577 800);
FORCEADD TAP..6
(-5575 4400);
FORCEPROP 3 LASTPIN (-5525 4400) SIG_NAME M_C_DQ<57>
J 0
(-5515 4410);
DISPLAY 0.659574 (-5515 4410);
PAINT MONO (-5515 4410);
DISPLAY INVISIBLE (-5515 4410);
FORCEPROP 1 LASTPIN (-5525 4400) BN 57
J 0
(-5577 4408);
DISPLAY 0.617021 (-5577 4408);
PAINT PINK (-5577 4408);
FORCEPROP 2 LAST CDS_LIB mstr_standard
J 0
(-5575 4400);
PAINT MONO (-5575 4400);
DISPLAY INVISIBLE (-5575 4400);
FORCEPROP 1 LAST BODY_TYPE PLUMBING
J 0
(-5575 4350);
DISPLAY 1.595745 (-5575 4350);
PAINT GREEN (-5575 4350);
DISPLAY INVISIBLE (-5575 4350);
FORCEPROP 1 LAST HDL_TAP TRUE
J 0
(-5250 4275);
DISPLAY 1.595745 (-5250 4275);
PAINT GREEN (-5250 4275);
DISPLAY INVISIBLE (-5250 4275);
FORCEPROP 1 LAST PATH I80
J 0
(-5577 4400);
DISPLAY 0.872340 (-5577 4400);
PAINT GREEN (-5577 4400);
DISPLAY INVISIBLE (-5577 4400);
FORCEADD TAP..6
(-5575 4450);
FORCEPROP 3 LASTPIN (-5525 4450) SIG_NAME M_C_DQ<58>
J 0
(-5515 4460);
DISPLAY 0.659574 (-5515 4460);
PAINT MONO (-5515 4460);
DISPLAY INVISIBLE (-5515 4460);
FORCEPROP 1 LASTPIN (-5525 4450) BN 58
J 0
(-5577 4458);
DISPLAY 0.617021 (-5577 4458);
PAINT PINK (-5577 4458);
FORCEPROP 2 LAST CDS_LIB mstr_standard
J 0
(-5575 4450);
PAINT MONO (-5575 4450);
DISPLAY INVISIBLE (-5575 4450);
FORCEPROP 1 LAST BODY_TYPE PLUMBING
J 0
(-5575 4400);
DISPLAY 1.595745 (-5575 4400);
PAINT GREEN (-5575 4400);
DISPLAY INVISIBLE (-5575 4400);
FORCEPROP 1 LAST HDL_TAP TRUE
J 0
(-5250 4325);
DISPLAY 1.595745 (-5250 4325);
PAINT GREEN (-5250 4325);
DISPLAY INVISIBLE (-5250 4325);
FORCEPROP 1 LAST PATH I81
J 0
(-5577 4450);
DISPLAY 0.872340 (-5577 4450);
PAINT GREEN (-5577 4450);
DISPLAY INVISIBLE (-5577 4450);
FORCEADD TAP..6
(-5575 4500);
FORCEPROP 3 LASTPIN (-5525 4500) SIG_NAME M_C_DQ<59>
J 0
(-5515 4510);
DISPLAY 0.659574 (-5515 4510);
PAINT MONO (-5515 4510);
DISPLAY INVISIBLE (-5515 4510);
FORCEPROP 1 LASTPIN (-5525 4500) BN 59
J 0
(-5577 4508);
DISPLAY 0.617021 (-5577 4508);
PAINT PINK (-5577 4508);
FORCEPROP 2 LAST CDS_LIB mstr_standard
J 0
(-5575 4500);
PAINT MONO (-5575 4500);
DISPLAY INVISIBLE (-5575 4500);
FORCEPROP 1 LAST BODY_TYPE PLUMBING
J 0
(-5575 4450);
DISPLAY 1.595745 (-5575 4450);
PAINT GREEN (-5575 4450);
DISPLAY INVISIBLE (-5575 4450);
FORCEPROP 1 LAST HDL_TAP TRUE
J 0
(-5250 4375);
DISPLAY 1.595745 (-5250 4375);
PAINT GREEN (-5250 4375);
DISPLAY INVISIBLE (-5250 4375);
FORCEPROP 1 LAST PATH I82
J 0
(-5577 4500);
DISPLAY 0.872340 (-5577 4500);
PAINT GREEN (-5577 4500);
DISPLAY INVISIBLE (-5577 4500);
FORCEADD TAP..6
(-5575 4550);
FORCEPROP 3 LASTPIN (-5525 4550) SIG_NAME M_C_DQ<60>
J 0
(-5515 4560);
DISPLAY 0.659574 (-5515 4560);
PAINT MONO (-5515 4560);
DISPLAY INVISIBLE (-5515 4560);
FORCEPROP 1 LASTPIN (-5525 4550) BN 60
J 0
(-5577 4558);
DISPLAY 0.617021 (-5577 4558);
PAINT PINK (-5577 4558);
FORCEPROP 2 LAST CDS_LIB mstr_standard
J 0
(-5575 4550);
PAINT MONO (-5575 4550);
DISPLAY INVISIBLE (-5575 4550);
FORCEPROP 1 LAST BODY_TYPE PLUMBING
J 0
(-5575 4500);
DISPLAY 1.595745 (-5575 4500);
PAINT GREEN (-5575 4500);
DISPLAY INVISIBLE (-5575 4500);
FORCEPROP 1 LAST HDL_TAP TRUE
J 0
(-5250 4425);
DISPLAY 1.595745 (-5250 4425);
PAINT GREEN (-5250 4425);
DISPLAY INVISIBLE (-5250 4425);
FORCEPROP 1 LAST PATH I83
J 0
(-5577 4550);
DISPLAY 0.872340 (-5577 4550);
PAINT GREEN (-5577 4550);
DISPLAY INVISIBLE (-5577 4550);
FORCEADD TAP..6
(-5575 4600);
FORCEPROP 3 LASTPIN (-5525 4600) SIG_NAME M_C_DQ<61>
J 0
(-5515 4610);
DISPLAY 0.659574 (-5515 4610);
PAINT MONO (-5515 4610);
DISPLAY INVISIBLE (-5515 4610);
FORCEPROP 1 LASTPIN (-5525 4600) BN 61
J 0
(-5577 4608);
DISPLAY 0.617021 (-5577 4608);
PAINT PINK (-5577 4608);
FORCEPROP 2 LAST CDS_LIB mstr_standard
J 0
(-5575 4600);
PAINT MONO (-5575 4600);
DISPLAY INVISIBLE (-5575 4600);
FORCEPROP 1 LAST BODY_TYPE PLUMBING
J 0
(-5575 4550);
DISPLAY 1.595745 (-5575 4550);
PAINT GREEN (-5575 4550);
DISPLAY INVISIBLE (-5575 4550);
FORCEPROP 1 LAST HDL_TAP TRUE
J 0
(-5250 4475);
DISPLAY 1.595745 (-5250 4475);
PAINT GREEN (-5250 4475);
DISPLAY INVISIBLE (-5250 4475);
FORCEPROP 1 LAST PATH I84
J 0
(-5577 4600);
DISPLAY 0.872340 (-5577 4600);
PAINT GREEN (-5577 4600);
DISPLAY INVISIBLE (-5577 4600);
FORCEADD TAP..6
(-5575 4700);
FORCEPROP 3 LASTPIN (-5525 4700) SIG_NAME M_C_DQ<63>
J 0
(-5515 4710);
DISPLAY 0.659574 (-5515 4710);
PAINT MONO (-5515 4710);
DISPLAY INVISIBLE (-5515 4710);
FORCEPROP 1 LASTPIN (-5525 4700) BN 63
J 0
(-5577 4708);
DISPLAY 0.617021 (-5577 4708);
PAINT PINK (-5577 4708);
FORCEPROP 2 LAST CDS_LIB mstr_standard
J 0
(-5575 4700);
PAINT MONO (-5575 4700);
DISPLAY INVISIBLE (-5575 4700);
FORCEPROP 1 LAST BODY_TYPE PLUMBING
J 0
(-5575 4650);
DISPLAY 1.595745 (-5575 4650);
PAINT GREEN (-5575 4650);
DISPLAY INVISIBLE (-5575 4650);
FORCEPROP 1 LAST HDL_TAP TRUE
J 0
(-5250 4575);
DISPLAY 1.595745 (-5250 4575);
PAINT GREEN (-5250 4575);
DISPLAY INVISIBLE (-5250 4575);
FORCEPROP 1 LAST PATH I85
J 0
(-5577 4700);
DISPLAY 0.872340 (-5577 4700);
PAINT GREEN (-5577 4700);
DISPLAY INVISIBLE (-5577 4700);
FORCEADD TAP..6
(-5575 4650);
FORCEPROP 3 LASTPIN (-5525 4650) SIG_NAME M_C_DQ<62>
J 0
(-5515 4660);
DISPLAY 0.659574 (-5515 4660);
PAINT MONO (-5515 4660);
DISPLAY INVISIBLE (-5515 4660);
FORCEPROP 1 LASTPIN (-5525 4650) BN 62
J 0
(-5577 4658);
DISPLAY 0.617021 (-5577 4658);
PAINT PINK (-5577 4658);
FORCEPROP 2 LAST CDS_LIB mstr_standard
J 0
(-5575 4650);
PAINT MONO (-5575 4650);
DISPLAY INVISIBLE (-5575 4650);
FORCEPROP 1 LAST BODY_TYPE PLUMBING
J 0
(-5575 4600);
DISPLAY 1.595745 (-5575 4600);
PAINT GREEN (-5575 4600);
DISPLAY INVISIBLE (-5575 4600);
FORCEPROP 1 LAST HDL_TAP TRUE
J 0
(-5250 4525);
DISPLAY 1.595745 (-5250 4525);
PAINT GREEN (-5250 4525);
DISPLAY INVISIBLE (-5250 4525);
FORCEPROP 1 LAST PATH I86
J 0
(-5577 4650);
DISPLAY 0.872340 (-5577 4650);
PAINT GREEN (-5577 4650);
DISPLAY INVISIBLE (-5577 4650);
FORCEADD TAP..6
R 2
(-2850 750);
FORCEPROP 3 LASTPIN (-2900 750) SIG_NAME M_C_BA<0>
J 0
(-2890 760);
DISPLAY 0.659574 (-2890 760);
PAINT MONO (-2890 760);
DISPLAY INVISIBLE (-2890 760);
FORCEPROP 1 LASTPIN (-2900 750) BN 0
J 2
(-2848 758);
DISPLAY 0.617021 (-2848 758);
PAINT PINK (-2848 758);
FORCEPROP 2 LAST CDS_LIB mstr_standard
J 0
(-2850 750);
PAINT MONO (-2850 750);
DISPLAY INVISIBLE (-2850 750);
FORCEPROP 1 LAST BODY_TYPE PLUMBING
J 2
(-2850 700);
DISPLAY 1.595745 (-2850 700);
PAINT GREEN (-2850 700);
DISPLAY INVISIBLE (-2850 700);
FORCEPROP 1 LAST HDL_TAP TRUE
J 2
(-3175 625);
DISPLAY 1.595745 (-3175 625);
PAINT GREEN (-3175 625);
DISPLAY INVISIBLE (-3175 625);
FORCEPROP 1 LAST PATH I87
J 2
(-2848 750);
DISPLAY 0.872340 (-2848 750);
PAINT GREEN (-2848 750);
DISPLAY INVISIBLE (-2848 750);
FORCEADD TAP..6
R 2
(-2850 800);
FORCEPROP 3 LASTPIN (-2900 800) SIG_NAME M_C_BA<1>
J 0
(-2890 810);
DISPLAY 0.659574 (-2890 810);
PAINT MONO (-2890 810);
DISPLAY INVISIBLE (-2890 810);
FORCEPROP 1 LASTPIN (-2900 800) BN 1
J 2
(-2848 808);
DISPLAY 0.617021 (-2848 808);
PAINT PINK (-2848 808);
FORCEPROP 2 LAST CDS_LIB mstr_standard
J 0
(-2850 800);
PAINT MONO (-2850 800);
DISPLAY INVISIBLE (-2850 800);
FORCEPROP 1 LAST BODY_TYPE PLUMBING
J 2
(-2850 750);
DISPLAY 1.595745 (-2850 750);
PAINT GREEN (-2850 750);
DISPLAY INVISIBLE (-2850 750);
FORCEPROP 1 LAST HDL_TAP TRUE
J 2
(-3175 675);
DISPLAY 1.595745 (-3175 675);
PAINT GREEN (-3175 675);
DISPLAY INVISIBLE (-3175 675);
FORCEPROP 1 LAST PATH I88
J 2
(-2848 800);
DISPLAY 0.872340 (-2848 800);
PAINT GREEN (-2848 800);
DISPLAY INVISIBLE (-2848 800);
FORCEADD TAP..6
R 2
(-2850 850);
FORCEPROP 3 LASTPIN (-2900 850) SIG_NAME M_C_BG<0>
J 0
(-2890 860);
DISPLAY 0.659574 (-2890 860);
PAINT MONO (-2890 860);
DISPLAY INVISIBLE (-2890 860);
FORCEPROP 1 LASTPIN (-2900 850) BN 0
J 2
(-2848 858);
DISPLAY 0.617021 (-2848 858);
PAINT PINK (-2848 858);
FORCEPROP 2 LAST CDS_LIB mstr_standard
J 0
(-2850 850);
PAINT MONO (-2850 850);
DISPLAY INVISIBLE (-2850 850);
FORCEPROP 1 LAST BODY_TYPE PLUMBING
J 2
(-2850 800);
DISPLAY 1.595745 (-2850 800);
PAINT GREEN (-2850 800);
DISPLAY INVISIBLE (-2850 800);
FORCEPROP 1 LAST HDL_TAP TRUE
J 2
(-3175 725);
DISPLAY 1.595745 (-3175 725);
PAINT GREEN (-3175 725);
DISPLAY INVISIBLE (-3175 725);
FORCEPROP 1 LAST PATH I89
J 2
(-2848 850);
DISPLAY 0.872340 (-2848 850);
PAINT GREEN (-2848 850);
DISPLAY INVISIBLE (-2848 850);
FORCEADD TAP..6
(-5575 850);
FORCEPROP 3 LASTPIN (-5525 850) SIG_NAME M_C_CLK_DP<0>
J 0
(-5515 860);
DISPLAY 0.659574 (-5515 860);
PAINT MONO (-5515 860);
DISPLAY INVISIBLE (-5515 860);
FORCEPROP 1 LASTPIN (-5525 850) BN 0
J 0
(-5577 858);
DISPLAY 0.617021 (-5577 858);
PAINT PINK (-5577 858);
FORCEPROP 2 LAST CDS_LIB mstr_standard
J 0
(-5575 850);
PAINT MONO (-5575 850);
DISPLAY INVISIBLE (-5575 850);
FORCEPROP 1 LAST BODY_TYPE PLUMBING
J 0
(-5575 800);
DISPLAY 1.595745 (-5575 800);
PAINT GREEN (-5575 800);
DISPLAY INVISIBLE (-5575 800);
FORCEPROP 1 LAST HDL_TAP TRUE
J 0
(-5250 725);
DISPLAY 1.595745 (-5250 725);
PAINT GREEN (-5250 725);
DISPLAY INVISIBLE (-5250 725);
FORCEPROP 1 LAST PATH I9
J 0
(-5577 850);
DISPLAY 0.872340 (-5577 850);
PAINT GREEN (-5577 850);
DISPLAY INVISIBLE (-5577 850);
FORCEADD TAP..6
R 2
(-2850 900);
FORCEPROP 3 LASTPIN (-2900 900) SIG_NAME M_C_BG<1>
J 0
(-2890 910);
DISPLAY 0.659574 (-2890 910);
PAINT MONO (-2890 910);
DISPLAY INVISIBLE (-2890 910);
FORCEPROP 1 LASTPIN (-2900 900) BN 1
J 2
(-2848 908);
DISPLAY 0.617021 (-2848 908);
PAINT PINK (-2848 908);
FORCEPROP 2 LAST CDS_LIB mstr_standard
J 0
(-2850 900);
PAINT MONO (-2850 900);
DISPLAY INVISIBLE (-2850 900);
FORCEPROP 1 LAST BODY_TYPE PLUMBING
J 2
(-2850 850);
DISPLAY 1.595745 (-2850 850);
PAINT GREEN (-2850 850);
DISPLAY INVISIBLE (-2850 850);
FORCEPROP 1 LAST HDL_TAP TRUE
J 2
(-3175 775);
DISPLAY 1.595745 (-3175 775);
PAINT GREEN (-3175 775);
DISPLAY INVISIBLE (-3175 775);
FORCEPROP 1 LAST PATH I90
J 2
(-2848 900);
DISPLAY 0.872340 (-2848 900);
PAINT GREEN (-2848 900);
DISPLAY INVISIBLE (-2848 900);
FORCEADD TAP..6
R 2
(-2850 1000);
FORCEPROP 3 LASTPIN (-2900 1000) SIG_NAME M_C_CS_N<0>
J 0
(-2890 1010);
DISPLAY 0.659574 (-2890 1010);
PAINT MONO (-2890 1010);
DISPLAY INVISIBLE (-2890 1010);
FORCEPROP 1 LASTPIN (-2900 1000) BN 0
J 2
(-2848 1008);
DISPLAY 0.617021 (-2848 1008);
PAINT PINK (-2848 1008);
FORCEPROP 2 LAST CDS_LIB mstr_standard
J 0
(-2850 1000);
PAINT MONO (-2850 1000);
DISPLAY INVISIBLE (-2850 1000);
FORCEPROP 1 LAST BODY_TYPE PLUMBING
J 2
(-2850 950);
DISPLAY 1.595745 (-2850 950);
PAINT GREEN (-2850 950);
DISPLAY INVISIBLE (-2850 950);
FORCEPROP 1 LAST HDL_TAP TRUE
J 2
(-3175 875);
DISPLAY 1.595745 (-3175 875);
PAINT GREEN (-3175 875);
DISPLAY INVISIBLE (-3175 875);
FORCEPROP 1 LAST PATH I91
J 2
(-2848 1000);
DISPLAY 0.872340 (-2848 1000);
PAINT GREEN (-2848 1000);
DISPLAY INVISIBLE (-2848 1000);
FORCEADD TAP..6
R 2
(-2850 1100);
FORCEPROP 3 LASTPIN (-2900 1100) SIG_NAME M_C_CS_N<2>
J 0
(-2890 1110);
DISPLAY 0.659574 (-2890 1110);
PAINT MONO (-2890 1110);
DISPLAY INVISIBLE (-2890 1110);
FORCEPROP 1 LASTPIN (-2900 1100) BN 2
J 2
(-2848 1108);
DISPLAY 0.617021 (-2848 1108);
PAINT PINK (-2848 1108);
FORCEPROP 2 LAST CDS_LIB mstr_standard
J 0
(-2850 1100);
PAINT MONO (-2850 1100);
DISPLAY INVISIBLE (-2850 1100);
FORCEPROP 1 LAST BODY_TYPE PLUMBING
J 2
(-2850 1050);
DISPLAY 1.595745 (-2850 1050);
PAINT GREEN (-2850 1050);
DISPLAY INVISIBLE (-2850 1050);
FORCEPROP 1 LAST HDL_TAP TRUE
J 2
(-3175 975);
DISPLAY 1.595745 (-3175 975);
PAINT GREEN (-3175 975);
DISPLAY INVISIBLE (-3175 975);
FORCEPROP 1 LAST PATH I92
J 2
(-2848 1100);
DISPLAY 0.872340 (-2848 1100);
PAINT GREEN (-2848 1100);
DISPLAY INVISIBLE (-2848 1100);
FORCEADD TAP..6
R 2
(-2850 1050);
FORCEPROP 3 LASTPIN (-2900 1050) SIG_NAME M_C_CS_N<1>
J 0
(-2890 1060);
DISPLAY 0.659574 (-2890 1060);
PAINT MONO (-2890 1060);
DISPLAY INVISIBLE (-2890 1060);
FORCEPROP 1 LASTPIN (-2900 1050) BN 1
J 2
(-2848 1058);
DISPLAY 0.617021 (-2848 1058);
PAINT PINK (-2848 1058);
FORCEPROP 2 LAST CDS_LIB mstr_standard
J 0
(-2850 1050);
PAINT MONO (-2850 1050);
DISPLAY INVISIBLE (-2850 1050);
FORCEPROP 1 LAST BODY_TYPE PLUMBING
J 2
(-2850 1000);
DISPLAY 1.595745 (-2850 1000);
PAINT GREEN (-2850 1000);
DISPLAY INVISIBLE (-2850 1000);
FORCEPROP 1 LAST HDL_TAP TRUE
J 2
(-3175 925);
DISPLAY 1.595745 (-3175 925);
PAINT GREEN (-3175 925);
DISPLAY INVISIBLE (-3175 925);
FORCEPROP 1 LAST PATH I93
J 2
(-2848 1050);
DISPLAY 0.872340 (-2848 1050);
PAINT GREEN (-2848 1050);
DISPLAY INVISIBLE (-2848 1050);
FORCEADD TAP..6
R 2
(-2850 1200);
FORCEPROP 3 LASTPIN (-2900 1200) SIG_NAME M_C_CS_N<4>
J 0
(-2890 1210);
DISPLAY 0.659574 (-2890 1210);
PAINT MONO (-2890 1210);
DISPLAY INVISIBLE (-2890 1210);
FORCEPROP 1 LASTPIN (-2900 1200) BN 4
J 2
(-2848 1208);
DISPLAY 0.617021 (-2848 1208);
PAINT PINK (-2848 1208);
FORCEPROP 2 LAST CDS_LIB mstr_standard
J 0
(-2850 1200);
PAINT MONO (-2850 1200);
DISPLAY INVISIBLE (-2850 1200);
FORCEPROP 1 LAST BODY_TYPE PLUMBING
J 2
(-2850 1150);
DISPLAY 1.595745 (-2850 1150);
PAINT GREEN (-2850 1150);
DISPLAY INVISIBLE (-2850 1150);
FORCEPROP 1 LAST HDL_TAP TRUE
J 2
(-3175 1075);
DISPLAY 1.595745 (-3175 1075);
PAINT GREEN (-3175 1075);
DISPLAY INVISIBLE (-3175 1075);
FORCEPROP 1 LAST PATH I94
J 2
(-2848 1200);
DISPLAY 0.872340 (-2848 1200);
PAINT GREEN (-2848 1200);
DISPLAY INVISIBLE (-2848 1200);
FORCEADD TAP..6
R 2
(-2850 1150);
FORCEPROP 3 LASTPIN (-2900 1150) SIG_NAME M_C_CS_N<3>
J 0
(-2890 1160);
DISPLAY 0.659574 (-2890 1160);
PAINT MONO (-2890 1160);
DISPLAY INVISIBLE (-2890 1160);
FORCEPROP 1 LASTPIN (-2900 1150) BN 3
J 2
(-2848 1158);
DISPLAY 0.617021 (-2848 1158);
PAINT PINK (-2848 1158);
FORCEPROP 2 LAST CDS_LIB mstr_standard
J 0
(-2850 1150);
PAINT MONO (-2850 1150);
DISPLAY INVISIBLE (-2850 1150);
FORCEPROP 1 LAST BODY_TYPE PLUMBING
J 2
(-2850 1100);
DISPLAY 1.595745 (-2850 1100);
PAINT GREEN (-2850 1100);
DISPLAY INVISIBLE (-2850 1100);
FORCEPROP 1 LAST HDL_TAP TRUE
J 2
(-3175 1025);
DISPLAY 1.595745 (-3175 1025);
PAINT GREEN (-3175 1025);
DISPLAY INVISIBLE (-3175 1025);
FORCEPROP 1 LAST PATH I95
J 2
(-2848 1150);
DISPLAY 0.872340 (-2848 1150);
PAINT GREEN (-2848 1150);
DISPLAY INVISIBLE (-2848 1150);
FORCEADD TAP..6
R 2
(-2850 1250);
FORCEPROP 3 LASTPIN (-2900 1250) SIG_NAME M_C_CS_N<5>
J 0
(-2890 1260);
DISPLAY 0.659574 (-2890 1260);
PAINT MONO (-2890 1260);
DISPLAY INVISIBLE (-2890 1260);
FORCEPROP 1 LASTPIN (-2900 1250) BN 5
J 2
(-2848 1258);
DISPLAY 0.617021 (-2848 1258);
PAINT PINK (-2848 1258);
FORCEPROP 2 LAST CDS_LIB mstr_standard
J 0
(-2850 1250);
PAINT MONO (-2850 1250);
DISPLAY INVISIBLE (-2850 1250);
FORCEPROP 1 LAST BODY_TYPE PLUMBING
J 2
(-2850 1200);
DISPLAY 1.595745 (-2850 1200);
PAINT GREEN (-2850 1200);
DISPLAY INVISIBLE (-2850 1200);
FORCEPROP 1 LAST HDL_TAP TRUE
J 2
(-3175 1125);
DISPLAY 1.595745 (-3175 1125);
PAINT GREEN (-3175 1125);
DISPLAY INVISIBLE (-3175 1125);
FORCEPROP 1 LAST PATH I96
J 2
(-2848 1250);
DISPLAY 0.872340 (-2848 1250);
PAINT GREEN (-2848 1250);
DISPLAY INVISIBLE (-2848 1250);
FORCEADD TAP..6
R 2
(-2850 1300);
FORCEPROP 3 LASTPIN (-2900 1300) SIG_NAME M_C_CS_N<6>
J 0
(-2890 1310);
DISPLAY 0.659574 (-2890 1310);
PAINT MONO (-2890 1310);
DISPLAY INVISIBLE (-2890 1310);
FORCEPROP 1 LASTPIN (-2900 1300) BN 6
J 2
(-2848 1308);
DISPLAY 0.617021 (-2848 1308);
PAINT PINK (-2848 1308);
FORCEPROP 2 LAST CDS_LIB mstr_standard
J 0
(-2850 1300);
PAINT MONO (-2850 1300);
DISPLAY INVISIBLE (-2850 1300);
FORCEPROP 1 LAST BODY_TYPE PLUMBING
J 2
(-2850 1250);
DISPLAY 1.595745 (-2850 1250);
PAINT GREEN (-2850 1250);
DISPLAY INVISIBLE (-2850 1250);
FORCEPROP 1 LAST HDL_TAP TRUE
J 2
(-3175 1175);
DISPLAY 1.595745 (-3175 1175);
PAINT GREEN (-3175 1175);
DISPLAY INVISIBLE (-3175 1175);
FORCEPROP 1 LAST PATH I97
J 2
(-2848 1300);
DISPLAY 0.872340 (-2848 1300);
PAINT GREEN (-2848 1300);
DISPLAY INVISIBLE (-2848 1300);
FORCEADD TAP..6
R 2
(-2850 1350);
FORCEPROP 3 LASTPIN (-2900 1350) SIG_NAME M_C_CS_N<7>
J 0
(-2890 1360);
DISPLAY 0.659574 (-2890 1360);
PAINT MONO (-2890 1360);
DISPLAY INVISIBLE (-2890 1360);
FORCEPROP 1 LASTPIN (-2900 1350) BN 7
J 2
(-2848 1358);
DISPLAY 0.617021 (-2848 1358);
PAINT PINK (-2848 1358);
FORCEPROP 2 LAST CDS_LIB mstr_standard
J 0
(-2850 1350);
PAINT MONO (-2850 1350);
DISPLAY INVISIBLE (-2850 1350);
FORCEPROP 1 LAST BODY_TYPE PLUMBING
J 2
(-2850 1300);
DISPLAY 1.595745 (-2850 1300);
PAINT GREEN (-2850 1300);
DISPLAY INVISIBLE (-2850 1300);
FORCEPROP 1 LAST HDL_TAP TRUE
J 2
(-3175 1225);
DISPLAY 1.595745 (-3175 1225);
PAINT GREEN (-3175 1225);
DISPLAY INVISIBLE (-3175 1225);
FORCEPROP 1 LAST PATH I98
J 2
(-2848 1350);
DISPLAY 0.872340 (-2848 1350);
PAINT GREEN (-2848 1350);
DISPLAY INVISIBLE (-2848 1350);
FORCEADD TAP..6
R 2
(-2850 1450);
FORCEPROP 3 LASTPIN (-2900 1450) SIG_NAME M_C_ODT<0>
J 0
(-2890 1460);
DISPLAY 0.659574 (-2890 1460);
PAINT MONO (-2890 1460);
DISPLAY INVISIBLE (-2890 1460);
FORCEPROP 1 LASTPIN (-2900 1450) BN 0
J 2
(-2848 1458);
DISPLAY 0.617021 (-2848 1458);
PAINT PINK (-2848 1458);
FORCEPROP 2 LAST CDS_LIB mstr_standard
J 0
(-2850 1450);
PAINT MONO (-2850 1450);
DISPLAY INVISIBLE (-2850 1450);
FORCEPROP 1 LAST BODY_TYPE PLUMBING
J 2
(-2850 1400);
DISPLAY 1.595745 (-2850 1400);
PAINT GREEN (-2850 1400);
DISPLAY INVISIBLE (-2850 1400);
FORCEPROP 1 LAST HDL_TAP TRUE
J 2
(-3175 1325);
DISPLAY 1.595745 (-3175 1325);
PAINT GREEN (-3175 1325);
DISPLAY INVISIBLE (-3175 1325);
FORCEPROP 1 LAST PATH I99
J 2
(-2848 1450);
DISPLAY 0.872340 (-2848 1450);
PAINT GREEN (-2848 1450);
DISPLAY INVISIBLE (-2848 1450);
FORCEADD PRELIM..10
(-4215 2590);
PAINT GRAY (-4215 2590);
FORCEPROP 2 LAST CDS_LIB mstr_misc
J 0
(-4215 2590);
PAINT ORANGE (-4215 2590);
DISPLAY INVISIBLE (-4215 2590);
FORCEPROP 1 LAST COMMENT_BODY TRUE
J 0
(-4215 2590);
PAINT ORANGE (-4215 2590);
DISPLAY INVISIBLE (-4215 2590);
FORCEADD DESIGN_NOTE..1
(-6400 425);
FORCEPROP 0 LAST L1 CPU SYMBOLS 1-30 ARE PRELIMINARY AND SUBJECT TO CHANGE
J 0
(-6600 300);
DISPLAY 1.021277 (-6600 300);
PAINT ORANGE (-6600 300);
FORCEPROP 2 LAST CDS_LIB mstr_symbols
J 0
(-6400 425);
PAINT ORANGE (-6400 425);
DISPLAY INVISIBLE (-6400 425);
FORCEPROP 1 LAST COMMENT_BODY TRUE
J 0
(-6375 525);
DISPLAY 0.978723 (-6375 525);
PAINT ORANGE (-6375 525);
DISPLAY INVISIBLE (-6375 525);
FORCEADD INTEL_CORP_BPAGE..1
(0 0);
FORCEPROP 1 LAST CDS_CON_LAST_MODIFIED Tue Dec 01 11:51:17 2015
J 0
(-1425 325);
DISPLAY 1.340426 (-1425 325);
PAINT GREEN (-1425 325);
DISPLAY INVISIBLE (-1425 325);
FORCEPROP 1 LAST CUSTOM_TXT_CDS <CURRENT_DESIGN_SHEET> OF <TOTAL_DESIGN_SHEETS>
J 0
(-500 25);
PAINT GREEN (-500 25);
FORCEPROP 1 LAST CUSTOM_TXT_CDS <CON_LAST_MODIFIED>
J 0
(-1925 350);
PAINT GREEN (-1925 350);
FORCEPROP 2 LAST CUSTOM_TXT_CDS <XR_PAGE_TITLE>
J 0
(-7890 5250);
DISPLAY 0.638298 (-7890 5250);
PAINT PINK (-7890 5250);
DISPLAY INVISIBLE (-7890 5250);
FORCEPROP 1 LAST SCH_ADDRESS3 Santa Clara, CA 95052-8119
J 0
(-3975 25);
DISPLAY 0.617021 (-3975 25);
PAINT GREEN (-3975 25);
FORCEPROP 1 LAST SCH_ADDRESS2 P.O. BOX 58119
J 0
(-3975 75);
DISPLAY 0.617021 (-3975 75);
PAINT GREEN (-3975 75);
FORCEPROP 1 LAST SCH_ADDRESS1 2200 Mission College Blvd.
J 0
(-3975 125);
DISPLAY 0.617021 (-3975 125);
PAINT GREEN (-3975 125);
FORCEPROP 1 LAST SCH_TITLE SKYLAKE - SKT0 - 5 OF 21
J 0
(-7950 50);
DISPLAY 1.212766 (-7950 50);
PAINT GREEN (-7950 50);
FORCEPROP 1 LAST SCH_NUMBER H4694802
J 0
(-1300 150);
DISPLAY 1.212766 (-1300 150);
PAINT YELLOW (-1300 150);
FORCEPROP 1 LAST SCH_DEPT BESD
J 1
(-4450 100);
DISPLAY 1.212766 (-4450 100);
PAINT YELLOW (-4450 100);
FORCEPROP 1 LAST SCH_REV 2.420
J 0
(-250 150);
DISPLAY 0.978723 (-250 150);
PAINT YELLOW (-250 150);
FORCEPROP 2 LAST CDS_LIB mstr_symbols
J 0
(0 0);
PAINT ORANGE (0 0);
DISPLAY INVISIBLE (0 0);
FORCEPROP 2 LAST PAGE_BORDER TRUE
J 0
(-7890 5250);
DISPLAY 0.851064 (-7890 5250);
PAINT PINK (-7890 5250);
DISPLAY INVISIBLE (-7890 5250);
FORCEPROP 1 LAST COMMENT_BODY TRUE
J 0
(12 12);
DISPLAY 0.638298 (12 12);
PAINT GREEN (12 12);
DISPLAY INVISIBLE (12 12);
FORCEPROP 2 LAST CDS_XR_PAGE_TITLE CR-25 : @BASEBOARD_FAB2_LIB.BASEBOARD_FAB2(SCH_1):PAGE25
J 0
(-7890 5250);
DISPLAY 0.638298 (-7890 5250);
PAINT PINK (-7890 5250);
DISPLAY INVISIBLE (-7890 5250);
WIRE 17 -1 (-2800 4075)(-2800 4125);
WIRE 17 -1 (-2800 4025)(-2800 4075);
WIRE 17 -1 (-2800 4125)(-2800 4175);
WIRE 17 -1 (-2800 4175)(-2800 4225);
WIRE 17 -1 (-2800 3975)(-2800 4025);
WIRE 17 -1 (-2800 3925)(-2800 3975);
WIRE 17 -1 (-2800 4225)(-2800 4275);
WIRE 17 -1 (-2800 4275)(-2800 4325);
WIRE 17 -1 (-2800 3875)(-2800 3925);
WIRE 17 -1 (-2800 4325)(-2800 4375);
WIRE 17 -1 (-2800 4375)(-2800 4425);
WIRE 17 -1 (-2800 4425)(-2800 4475);
WIRE 17 -1 (-2800 4475)(-2800 4525);
WIRE 17 -1 (-2800 4525)(-2800 4575);
WIRE 17 -1 (-2800 4575)(-2800 4625);
WIRE 17 -1 (-2800 4625)(-2800 4675);
WIRE 17 -1 (-2800 4675)(-2800 4725);
WIRE 17 -1 (-2800 4725)(-2800 4775);
WIRE 17 -1 (-2050 4775)(-2800 4775);
FORCEPROP 2 LAST SIG_NAME M_C_DQS_DP<17:0>
J 0
(-2700 4785);
DISPLAY 0.617021 (-2700 4785);
PAINT ORANGE (-2700 4785);
WIRE 17 -1 (-2800 2025)(-2800 2075);
WIRE 17 -1 (-2800 1975)(-2800 2025);
WIRE 17 -1 (-2800 2075)(-2800 2125);
WIRE 17 -1 (-2800 2125)(-2800 2175);
WIRE 17 -1 (-2800 2175)(-2800 2225);
WIRE 17 -1 (-2800 2225)(-2800 2275);
WIRE 17 -1 (-2800 2275)(-2800 2325);
WIRE 17 -1 (-2800 2325)(-2800 2375);
WIRE 17 -1 (-2800 2375)(-2800 2425);
WIRE 17 -1 (-2800 2425)(-2800 2475);
WIRE 17 -1 (-2800 2475)(-2800 2525);
WIRE 17 -1 (-2800 2525)(-2800 2575);
WIRE 17 -1 (-2800 2575)(-2800 2625);
WIRE 17 -1 (-2800 2625)(-2800 2675);
WIRE 17 -1 (-2800 2675)(-2800 2725);
WIRE 17 -1 (-2800 2725)(-2800 2775);
WIRE 17 -1 (-2800 2775)(-2800 2825);
WIRE 17 -1 (-2800 2825)(-2800 2850);
WIRE 17 -1 (-2050 2850)(-2800 2850);
FORCEPROP 2 LAST SIG_NAME M_C_MA<17:0>
J 0
(-2700 2860);
DISPLAY 0.617021 (-2700 2860);
PAINT ORANGE (-2700 2860);
WIRE 17 -1 (-2800 2925)(-2800 2975);
WIRE 17 -1 (-2800 2975)(-2800 3025);
WIRE 17 -1 (-2800 3025)(-2800 3075);
WIRE 17 -1 (-2800 3075)(-2800 3125);
WIRE 17 -1 (-2800 3125)(-2800 3175);
WIRE 17 -1 (-2800 3175)(-2800 3225);
WIRE 17 -1 (-2800 3225)(-2800 3275);
WIRE 17 -1 (-2800 3275)(-2800 3325);
WIRE 17 -1 (-2800 3325)(-2800 3375);
WIRE 17 -1 (-2800 3375)(-2800 3425);
WIRE 17 -1 (-2800 3425)(-2800 3475);
WIRE 17 -1 (-2800 3475)(-2800 3525);
WIRE 17 -1 (-2800 3525)(-2800 3575);
WIRE 17 -1 (-2800 3575)(-2800 3625);
WIRE 17 -1 (-2800 3625)(-2800 3675);
WIRE 17 -1 (-2800 3675)(-2800 3725);
WIRE 17 -1 (-2800 3725)(-2800 3775);
WIRE 17 -1 (-2800 3775)(-2800 3800);
WIRE 17 -1 (-2050 3800)(-2800 3800);
FORCEPROP 2 LAST SIG_NAME M_C_DQS_DN<17:0>
J 0
(-2700 3810);
DISPLAY 0.617021 (-2700 3810);
PAINT ORANGE (-2700 3810);
WIRE 17 -1 (-2800 1475)(-2800 1525);
WIRE 17 -1 (-2800 1525)(-2800 1575);
WIRE 17 -1 (-2800 1575)(-2800 1625);
WIRE 17 -1 (-2800 1625)(-2800 1650);
WIRE 17 -1 (-2050 1650)(-2800 1650);
FORCEPROP 2 LAST SIG_NAME M_C_ODT<3:0>
J 0
(-2700 1660);
DISPLAY 0.617021 (-2700 1660);
PAINT ORANGE (-2700 1660);
WIRE 17 -1 (-2800 1025)(-2800 1075);
WIRE 17 -1 (-2800 1075)(-2800 1125);
WIRE 17 -1 (-2800 1125)(-2800 1175);
WIRE 17 -1 (-2800 1175)(-2800 1225);
WIRE 17 -1 (-2800 1225)(-2800 1275);
WIRE 17 -1 (-2800 1275)(-2800 1325);
WIRE 17 -1 (-2800 1325)(-2800 1375);
WIRE 17 -1 (-2800 1375)(-2800 1400);
WIRE 17 -1 (-2050 1400)(-2800 1400);
FORCEPROP 2 LAST SIG_NAME M_C_CS_N<7:0>
J 0
(-2700 1410);
DISPLAY 0.617021 (-2700 1410);
PAINT ORANGE (-2700 1410);
WIRE 17 -1 (-2800 1725)(-2800 1775);
WIRE 17 -1 (-2800 1775)(-2800 1825);
WIRE 17 -1 (-2800 1825)(-2800 1875);
WIRE 17 -1 (-2800 1875)(-2800 1900);
WIRE 17 -1 (-2050 1900)(-2800 1900);
FORCEPROP 2 LAST SIG_NAME M_C_CKE<3:0>
J 0
(-2700 1910);
DISPLAY 0.617021 (-2700 1910);
PAINT ORANGE (-2700 1910);
WIRE 17 -1 (-2800 875)(-2800 925);
WIRE 17 -1 (-2800 925)(-2800 950);
WIRE 17 -1 (-2050 950)(-2800 950);
FORCEPROP 2 LAST SIG_NAME M_C_BG<1:0>
J 0
(-2700 960);
DISPLAY 0.617021 (-2700 960);
PAINT ORANGE (-2700 960);
WIRE 17 -1 (-2800 775)(-2800 825);
WIRE 17 -1 (-2800 825)(-2800 850);
WIRE 17 -1 (-2050 850)(-2800 850);
FORCEPROP 2 LAST SIG_NAME M_C_BA<1:0>
J 0
(-2700 860);
DISPLAY 0.617021 (-2700 860);
PAINT ORANGE (-2700 860);
WIRE 17 -1 (-5625 4075)(-5625 4125);
WIRE 17 -1 (-5625 4025)(-5625 4075);
WIRE 17 -1 (-5625 4125)(-5625 4175);
WIRE 17 -1 (-5625 4175)(-5625 4225);
WIRE 17 -1 (-5625 3975)(-5625 4025);
WIRE 17 -1 (-5625 3925)(-5625 3975);
WIRE 17 -1 (-5625 4225)(-5625 4275);
WIRE 17 -1 (-5625 4275)(-5625 4325);
WIRE 17 -1 (-5625 3875)(-5625 3925);
WIRE 17 -1 (-5625 3825)(-5625 3875);
WIRE 17 -1 (-5625 4325)(-5625 4375);
WIRE 17 -1 (-5625 4375)(-5625 4425);
WIRE 17 -1 (-5625 3775)(-5625 3825);
WIRE 17 -1 (-5625 3725)(-5625 3775);
WIRE 17 -1 (-5625 4425)(-5625 4475);
WIRE 17 -1 (-5625 4475)(-5625 4525);
WIRE 17 -1 (-5625 3675)(-5625 3725);
WIRE 17 -1 (-5625 3625)(-5625 3675);
WIRE 17 -1 (-5625 4525)(-5625 4575);
WIRE 17 -1 (-5625 4575)(-5625 4625);
WIRE 17 -1 (-5625 3575)(-5625 3625);
WIRE 17 -1 (-5625 3525)(-5625 3575);
WIRE 17 -1 (-5625 4625)(-5625 4675);
WIRE 17 -1 (-5625 4675)(-5625 4725);
WIRE 17 -1 (-5625 3475)(-5625 3525);
WIRE 17 -1 (-5625 3425)(-5625 3475);
WIRE 17 -1 (-5625 4725)(-5625 4825);
WIRE 17 -1 (-5625 4825)(-6375 4825);
FORCEPROP 2 LAST SIG_NAME M_C_DQ<63:0>
J 0
(-6325 4835);
DISPLAY 0.617021 (-6325 4835);
PAINT ORANGE (-6325 4835);
WIRE 17 -1 (-5625 2625)(-5625 2675);
WIRE 17 -1 (-5625 2575)(-5625 2625);
WIRE 17 -1 (-5625 2675)(-5625 2725);
WIRE 17 -1 (-5625 2725)(-5625 2775);
WIRE 17 -1 (-5625 2525)(-5625 2575);
WIRE 17 -1 (-5625 2475)(-5625 2525);
WIRE 17 -1 (-5625 2775)(-5625 2825);
WIRE 17 -1 (-5625 2825)(-5625 2875);
WIRE 17 -1 (-5625 2425)(-5625 2475);
WIRE 17 -1 (-5625 2375)(-5625 2425);
WIRE 17 -1 (-5625 2875)(-5625 2925);
WIRE 17 -1 (-5625 2925)(-5625 2975);
WIRE 17 -1 (-5625 2325)(-5625 2375);
WIRE 17 -1 (-5625 2275)(-5625 2325);
WIRE 17 -1 (-5625 2975)(-5625 3025);
WIRE 17 -1 (-5625 3025)(-5625 3075);
WIRE 17 -1 (-5625 2225)(-5625 2275);
WIRE 17 -1 (-5625 2175)(-5625 2225);
WIRE 17 -1 (-5625 3075)(-5625 3125);
WIRE 17 -1 (-5625 3125)(-5625 3175);
WIRE 17 -1 (-5625 2125)(-5625 2175);
WIRE 17 -1 (-5625 2075)(-5625 2125);
WIRE 17 -1 (-5625 3175)(-5625 3225);
WIRE 17 -1 (-5625 3225)(-5625 3275);
WIRE 17 -1 (-5625 2025)(-5625 2075);
WIRE 17 -1 (-5625 1975)(-5625 2025);
WIRE 17 -1 (-5625 3275)(-5625 3325);
WIRE 17 -1 (-5625 3325)(-5625 3375);
WIRE 17 -1 (-5625 1925)(-5625 1975);
WIRE 17 -1 (-5625 1875)(-5625 1925);
WIRE 17 -1 (-5625 3375)(-5625 3425);
WIRE 17 -1 (-5625 1825)(-5625 1875);
WIRE 17 -1 (-5625 1775)(-5625 1825);
WIRE 17 -1 (-5625 1725)(-5625 1775);
WIRE 17 -1 (-5625 1675)(-5625 1725);
WIRE 17 -1 (-5625 1625)(-5625 1675);
WIRE 17 -1 (-5625 1575)(-5625 1625);
WIRE 17 -1 (-5625 1125)(-5625 1175);
WIRE 17 -1 (-5625 1175)(-5625 1225);
WIRE 17 -1 (-5625 1225)(-5625 1275);
WIRE 17 -1 (-5625 1275)(-5625 1325);
WIRE 17 -1 (-5625 1325)(-5625 1375);
WIRE 17 -1 (-5625 1375)(-5625 1425);
WIRE 17 -1 (-5625 1425)(-5625 1475);
WIRE 17 -1 (-5625 1475)(-5625 1500);
WIRE 17 -1 (-5625 1500)(-6375 1500);
FORCEPROP 2 LAST SIG_NAME M_C_ECC<7:0>
J 0
(-6325 1510);
DISPLAY 0.617021 (-6325 1510);
PAINT ORANGE (-6325 1510);
WIRE 17 -1 (-5625 875)(-5625 925);
WIRE 17 -1 (-5625 925)(-5625 975);
WIRE 17 -1 (-5625 975)(-5625 1025);
WIRE 17 -1 (-5625 1025)(-5625 1050);
WIRE 17 -1 (-5625 1050)(-6375 1050);
FORCEPROP 2 LAST SIG_NAME M_C_CLK_DP<3:0>
J 0
(-6325 1060);
DISPLAY 0.617021 (-6325 1060);
PAINT ORANGE (-6325 1060);
WIRE 17 -1 (-5625 675)(-5625 725);
WIRE 17 -1 (-5625 725)(-5625 775);
WIRE 17 -1 (-5625 775)(-5625 825);
WIRE 17 -1 (-5625 825)(-5625 850);
WIRE 17 -1 (-5625 850)(-6375 850);
FORCEPROP 2 LAST SIG_NAME M_C_CLK_DN<3:0>
J 0
(-6325 860);
DISPLAY 0.617021 (-6325 860);
PAINT ORANGE (-6325 860);
WIRE 16 -1 (-5525 1750)(-5025 1750);
WIRE 16 -1 (-5025 550)(-6375 550);
FORCEPROP 2 LAST SIG_NAME M_C_C<2>
J 0
(-6325 560);
DISPLAY 0.617021 (-6325 560);
PAINT ORANGE (-6325 560);
WIRE 16 -1 (-5025 800)(-5525 800);
WIRE 16 -1 (-5025 750)(-5525 750);
WIRE 16 -1 (-5025 700)(-5525 700);
WIRE 16 -1 (-5025 650)(-5525 650);
WIRE 16 -1 (-5025 1000)(-5525 1000);
WIRE 16 -1 (-5025 950)(-5525 950);
WIRE 16 -1 (-5025 900)(-5525 900);
WIRE 16 -1 (-5025 850)(-5525 850);
WIRE 16 -1 (-5525 2000)(-5025 2000);
WIRE 16 -1 (-5525 1950)(-5025 1950);
WIRE 16 -1 (-5525 1900)(-5025 1900);
WIRE 16 -1 (-5025 1850)(-5525 1850);
WIRE 16 -1 (-5525 1800)(-5025 1800);
WIRE 16 -1 (-5025 1700)(-5525 1700);
WIRE 16 -1 (-5525 1650)(-5025 1650);
WIRE 16 -1 (-5525 1600)(-5025 1600);
WIRE 16 -1 (-5525 1550)(-5025 1550);
WIRE 16 -1 (-5025 1450)(-5525 1450);
WIRE 16 -1 (-5025 1400)(-5525 1400);
WIRE 16 -1 (-5025 1350)(-5525 1350);
WIRE 16 -1 (-5025 1300)(-5525 1300);
WIRE 16 -1 (-5025 1250)(-5525 1250);
WIRE 16 -1 (-5025 1200)(-5525 1200);
WIRE 16 -1 (-5025 1150)(-5525 1150);
WIRE 16 -1 (-5025 1100)(-5525 1100);
WIRE 16 -1 (-5025 4050)(-5525 4050);
WIRE 16 -1 (-5025 4000)(-5525 4000);
WIRE 16 -1 (-5025 3950)(-5525 3950);
WIRE 16 -1 (-5025 3900)(-5525 3900);
WIRE 16 -1 (-5025 3850)(-5525 3850);
WIRE 16 -1 (-5025 3800)(-5525 3800);
WIRE 16 -1 (-5025 3750)(-5525 3750);
WIRE 16 -1 (-5025 3700)(-5525 3700);
WIRE 16 -1 (-5525 3650)(-5025 3650);
WIRE 16 -1 (-5525 3600)(-5025 3600);
WIRE 16 -1 (-5025 3550)(-5525 3550);
WIRE 16 -1 (-5525 3500)(-5025 3500);
WIRE 16 -1 (-5525 3450)(-5025 3450);
WIRE 16 -1 (-5025 3400)(-5525 3400);
WIRE 16 -1 (-5525 3350)(-5025 3350);
WIRE 16 -1 (-5525 3300)(-5025 3300);
WIRE 16 -1 (-5525 3250)(-5025 3250);
WIRE 16 -1 (-5525 3200)(-5025 3200);
WIRE 16 -1 (-5525 3150)(-5025 3150);
WIRE 16 -1 (-5525 3100)(-5025 3100);
WIRE 16 -1 (-5025 3050)(-5525 3050);
WIRE 16 -1 (-5525 3000)(-5025 3000);
WIRE 16 -1 (-5525 2950)(-5025 2950);
WIRE 16 -1 (-5525 2900)(-5025 2900);
WIRE 16 -1 (-5525 2850)(-5025 2850);
WIRE 16 -1 (-5525 2800)(-5025 2800);
WIRE 16 -1 (-5525 2750)(-5025 2750);
WIRE 16 -1 (-5025 2700)(-5525 2700);
WIRE 16 -1 (-5525 2650)(-5025 2650);
WIRE 16 -1 (-5525 2550)(-5025 2550);
WIRE 16 -1 (-5525 2500)(-5025 2500);
WIRE 16 -1 (-5025 2450)(-5525 2450);
WIRE 16 -1 (-5525 2400)(-5025 2400);
WIRE 16 -1 (-5525 2350)(-5025 2350);
WIRE 16 -1 (-5025 2300)(-5525 2300);
WIRE 16 -1 (-5525 2250)(-5025 2250);
WIRE 16 -1 (-5525 2200)(-5025 2200);
WIRE 16 -1 (-5525 2150)(-5025 2150);
WIRE 16 -1 (-5525 2100)(-5025 2100);
WIRE 16 -1 (-5525 2050)(-5025 2050);
WIRE 16 -1 (-5525 2600)(-5025 2600);
WIRE 16 -1 (-5025 4700)(-5525 4700);
WIRE 16 -1 (-5025 4650)(-5525 4650);
WIRE 16 -1 (-5025 4600)(-5525 4600);
WIRE 16 -1 (-5025 4550)(-5525 4550);
WIRE 16 -1 (-5025 4500)(-5525 4500);
WIRE 16 -1 (-5025 4450)(-5525 4450);
WIRE 16 -1 (-5025 4400)(-5525 4400);
WIRE 16 -1 (-5025 4350)(-5525 4350);
WIRE 16 -1 (-5025 4300)(-5525 4300);
WIRE 16 -1 (-5025 4250)(-5525 4250);
WIRE 16 -1 (-5025 4200)(-5525 4200);
WIRE 16 -1 (-5025 4150)(-5525 4150);
WIRE 16 -1 (-5025 4100)(-5525 4100);
WIRE 16 -1 (-3325 800)(-2900 800);
WIRE 16 -1 (-3325 750)(-2900 750);
WIRE 16 -1 (-3325 900)(-2900 900);
WIRE 16 -1 (-3325 850)(-2900 850);
WIRE 16 -1 (-3325 1850)(-2900 1850);
WIRE 16 -1 (-3325 1800)(-2900 1800);
WIRE 16 -1 (-3325 1750)(-2900 1750);
WIRE 16 -1 (-3325 1700)(-2900 1700);
WIRE 16 -1 (-3325 1350)(-2900 1350);
WIRE 16 -1 (-3325 1300)(-2900 1300);
WIRE 16 -1 (-3325 1250)(-2900 1250);
WIRE 16 -1 (-3325 1200)(-2900 1200);
WIRE 16 -1 (-3325 1150)(-2900 1150);
WIRE 16 -1 (-3325 1100)(-2900 1100);
WIRE 16 -1 (-3325 1050)(-2900 1050);
WIRE 16 -1 (-3325 1000)(-2900 1000);
WIRE 16 -1 (-3325 2000)(-2900 2000);
WIRE 16 -1 (-3325 1950)(-2900 1950);
WIRE 16 -1 (-3325 1600)(-2900 1600);
WIRE 16 -1 (-3325 1550)(-2900 1550);
WIRE 16 -1 (-3325 1500)(-2900 1500);
WIRE 16 -1 (-3325 1450)(-2900 1450);
WIRE 16 -1 (-3325 550)(-2050 550);
FORCEPROP 2 LAST SIG_NAME M_C_PAR
J 0
(-2725 560);
DISPLAY 0.617021 (-2725 560);
PAINT ORANGE (-2725 560);
WIRE 16 -1 (-3325 650)(-2050 650);
FORCEPROP 2 LAST SIG_NAME M_C_ACT_N
J 0
(-2725 660);
DISPLAY 0.617021 (-2725 660);
PAINT ORANGE (-2725 660);
WIRE 16 -1 (-3325 600)(-2050 600);
FORCEPROP 2 LAST SIG_NAME M_C_ALERT_N
J 0
(-2725 610);
DISPLAY 0.617021 (-2725 610);
PAINT ORANGE (-2725 610);
WIRE 16 -1 (-3325 3750)(-2900 3750);
WIRE 16 -1 (-3325 3700)(-2900 3700);
WIRE 16 -1 (-3325 3650)(-2900 3650);
WIRE 16 -1 (-3325 3600)(-2900 3600);
WIRE 16 -1 (-3325 3550)(-2900 3550);
WIRE 16 -1 (-3325 3500)(-2900 3500);
WIRE 16 -1 (-3325 3450)(-2900 3450);
WIRE 16 -1 (-3325 3400)(-2900 3400);
WIRE 16 -1 (-3325 3350)(-2900 3350);
WIRE 16 -1 (-3325 3300)(-2900 3300);
WIRE 16 -1 (-3325 3250)(-2900 3250);
WIRE 16 -1 (-3325 3200)(-2900 3200);
WIRE 16 -1 (-3325 3150)(-2900 3150);
WIRE 16 -1 (-3325 3100)(-2900 3100);
WIRE 16 -1 (-3325 3050)(-2900 3050);
WIRE 16 -1 (-3325 3000)(-2900 3000);
WIRE 16 -1 (-3325 2950)(-2900 2950);
WIRE 16 -1 (-3325 2900)(-2900 2900);
WIRE 16 -1 (-3325 4050)(-2900 4050);
WIRE 16 -1 (-3325 4000)(-2900 4000);
WIRE 16 -1 (-3325 3950)(-2900 3950);
WIRE 16 -1 (-3325 3900)(-2900 3900);
WIRE 16 -1 (-3325 3850)(-2900 3850);
WIRE 16 -1 (-3325 2800)(-2900 2800);
WIRE 16 -1 (-3325 2750)(-2900 2750);
WIRE 16 -1 (-3325 2700)(-2900 2700);
WIRE 16 -1 (-3325 2650)(-2900 2650);
WIRE 16 -1 (-3325 2600)(-2900 2600);
WIRE 16 -1 (-3325 2550)(-2900 2550);
WIRE 16 -1 (-3325 2500)(-2900 2500);
WIRE 16 -1 (-3325 2450)(-2900 2450);
WIRE 16 -1 (-3325 2400)(-2900 2400);
WIRE 16 -1 (-3325 2350)(-2900 2350);
WIRE 16 -1 (-3325 2300)(-2900 2300);
WIRE 16 -1 (-3325 2250)(-2900 2250);
WIRE 16 -1 (-3325 2200)(-2900 2200);
WIRE 16 -1 (-3325 2150)(-2900 2150);
WIRE 16 -1 (-3325 2100)(-2900 2100);
WIRE 16 -1 (-3325 2050)(-2900 2050);
WIRE 16 -1 (-3325 4700)(-2900 4700);
WIRE 16 -1 (-3325 4650)(-2900 4650);
WIRE 16 -1 (-3325 4600)(-2900 4600);
WIRE 16 -1 (-3325 4550)(-2900 4550);
WIRE 16 -1 (-3325 4500)(-2900 4500);
WIRE 16 -1 (-3325 4450)(-2900 4450);
WIRE 16 -1 (-3325 4400)(-2900 4400);
WIRE 16 -1 (-3325 4350)(-2900 4350);
WIRE 16 -1 (-3325 4300)(-2900 4300);
WIRE 16 -1 (-3325 4250)(-2900 4250);
WIRE 16 -1 (-3325 4200)(-2900 4200);
WIRE 16 -1 (-3325 4150)(-2900 4150);
WIRE 16 -1 (-3325 4100)(-2900 4100);
FORCENOTE
ROOM=CPU0
(-7950 375) 0;
DISPLAY LEFT (-7950 375);
DISPLAY 1.382979 (-7950 375);
PAINT PURPLE (-7950 375);
FORCENOTE
BOM_COST=PROC_SOCKET
(-7950 250) 0;
DISPLAY LEFT (-7950 250);
DISPLAY 1.382979 (-7950 250);
PAINT PURPLE (-7950 250);
QUIT
